G04 ================== begin FILE IDENTIFICATION RECORD ==================*
G04 Layout Name:  14629-1a.brd*
G04 Film Name:    14629-1a_X_Y*
G04 File Format:  Gerber RS274X*
G04 File Origin:  Cadence Allegro 16.5-S037*
G04 Origin Date:  Tue Nov 25 11:50:33 2014*
G04 *
G04 Layer:  BOARD GEOMETRY/PANEL_DRAWING*
G04 *
G04 Offset:    (0.00 0.00)*
G04 Mirror:    No*
G04 Mode:      Positive*
G04 Rotation:  0*
G04 FullContactRelief:  No*
G04 UndefLineWidth:     6.00*
G04 ================== end FILE IDENTIFICATION RECORD ====================*
%FSLAX35Y35*MOIN*%
%IR0*IPPOS*OFA0.00000B0.00000*MIA0B0*SFA1.00000B1.00000*%
%ADD10C,.006*%
G75*
%LPD*%
G75*
G36*
G01X94313Y-588857D02*
X95504Y-599213D01*
X98239Y-589154D01*
X94313Y-588857D01*
G37*
G36*
G01X105605Y-630931D02*
X99595Y-622414D01*
X102017Y-632552D01*
X105605Y-630931D01*
G37*
G36*
G01X163339Y-561976D02*
X173576Y-563945D01*
Y-560008D01*
X163339Y-561976D01*
G37*
G36*
G01X157434D02*
X147198Y-560008D01*
Y-563945D01*
X157434Y-561976D01*
G37*
G36*
G01X925090Y-605512D02*
X923122Y-615748D01*
X927059D01*
X925090Y-605512D01*
G37*
G36*
G01Y-599213D02*
X927059Y-588976D01*
X923122D01*
X925090Y-599213D01*
G37*
G36*
G01X1941146Y144391D02*
X1949259Y150935D01*
X1946253Y153478D01*
X1941146Y144391D01*
G37*
G36*
G01X1924158Y135115D02*
X1917231Y142904D01*
X1914836Y139779D01*
X1924158Y135115D01*
G37*
G36*
G01X1947902Y921988D02*
X1956400Y928024D01*
X1953555Y930746D01*
X1947902Y921988D01*
G37*
G36*
G01X2348321Y501676D02*
X2340294Y495025D01*
X2343333Y492522D01*
X2348321Y501676D01*
G37*
G36*
G01X2404294Y958265D02*
X2413565Y963030D01*
X2411136Y966129D01*
X2404294Y958265D01*
G37*
G36*
G01X2423641Y169710D02*
X2432459Y175270D01*
X2429768Y178144D01*
X2423641Y169710D01*
G37*
G54D10*
G01X2870454Y-796310D02*
X-254151D01*
G01D02*
Y1400383D01*
G01X2851517Y-777373D02*
X-235214D01*
G01D02*
Y1381446D01*
G01X-246520Y-671993D02*
X-245545Y-673553D01*
X-244375Y-674593D01*
X-243010Y-675113D01*
X-241450Y-674593D01*
X-240280Y-673553D01*
X-239110Y-671993D01*
X-238720Y-669913D01*
Y-659513D01*
G01X-254151Y-561491D02*
X-235214D01*
G01X-244960Y-443630D02*
X-240280D01*
G01X-242620D02*
Y-459230D01*
G01X-244960D02*
X-240280D01*
G01X-254151Y-345608D02*
X-235214D01*
G01X-254151D02*
X-235214D01*
G01X-246715Y-243539D02*
Y-227939D01*
G01X-238525D02*
Y-243539D01*
G01Y-235739D02*
X-246715D01*
G01X-254151Y-129727D02*
X-235214D01*
G01X-254151D02*
X-235214D01*
G01X-241450Y-19856D02*
X-237550D01*
Y-24536D01*
X-238720Y-26096D01*
X-240085Y-27136D01*
X-242035Y-27656D01*
X-243985Y-27136D01*
X-245350Y-26096D01*
X-246520Y-24536D01*
X-247300Y-22716D01*
X-247690Y-20636D01*
Y-18816D01*
X-247300Y-17256D01*
X-246520Y-15436D01*
X-245350Y-13876D01*
X-244180Y-12836D01*
X-242620Y-12056D01*
X-241255D01*
X-239695Y-12576D01*
X-238525Y-13616D01*
G01X-254151Y86155D02*
X-235214D01*
G01X-254151D02*
X-235214D01*
G01X-246704Y188415D02*
Y204015D01*
X-239294D01*
G01X-242024Y196475D02*
X-246704D01*
G01X-254151Y302037D02*
X-235214D01*
G01X-254151D02*
X-235214D01*
G01X-254151D02*
X-235214D01*
G01X-238720Y404486D02*
X-246520D01*
Y420086D01*
X-238720D01*
G01X-241840Y412546D02*
X-246520D01*
G01X-254151Y517918D02*
X-235214D01*
G01X-254151D02*
X-235214D01*
G01X-246910Y620179D02*
Y635779D01*
X-243010D01*
X-241450Y634999D01*
X-240280Y633959D01*
X-239305Y632399D01*
X-238525Y630579D01*
X-238330Y627979D01*
X-238525Y625379D01*
X-239305Y623559D01*
X-240280Y621999D01*
X-241450Y620959D01*
X-243010Y620179D01*
X-246910D01*
G01X-254151Y733800D02*
X-235214D01*
G01X-254151D02*
X-235214D01*
G01X-238330Y850550D02*
X-239500Y851330D01*
X-240865Y851850D01*
X-242425D01*
X-244180Y851070D01*
X-245545Y849770D01*
X-246520Y848210D01*
X-247300Y845610D01*
X-247495Y843270D01*
X-247105Y840930D01*
X-246520Y839370D01*
X-245350Y837810D01*
X-243985Y836770D01*
X-242620Y836250D01*
X-241255D01*
X-239890Y836770D01*
X-238720Y837550D01*
X-237745Y838590D01*
G01X-254151Y949683D02*
X-235214D01*
G01X-254151D02*
X-235214D01*
G01X-241060Y1060262D02*
X-240280Y1061042D01*
X-239695Y1062342D01*
X-239305Y1064162D01*
X-239695Y1065722D01*
X-240475Y1066762D01*
X-241840Y1067542D01*
X-247105D01*
Y1051942D01*
X-240670D01*
X-239305Y1052982D01*
X-238525Y1054542D01*
X-238135Y1056362D01*
X-238525Y1058182D01*
X-239695Y1059742D01*
X-241060Y1060262D01*
X-247105D01*
G01X-254151Y1165564D02*
X-235214D01*
G01X-247495Y1267824D02*
X-242620Y1283424D01*
X-237745Y1267824D01*
G01X-239500Y1273284D02*
X-245740D01*
G01X-254151Y1400383D02*
X2870454D01*
G01X-235214Y1381446D02*
X2851517D01*
G01X-115742Y-792523D02*
Y-776923D01*
X-118082Y-780043D01*
G01Y-792523D02*
X-113402D01*
G01X-115059Y-11024D02*
X-115925Y-11313D01*
X-116575Y-12034D01*
X-117008Y-12900D01*
X-117333Y-14055D01*
X-117441Y-15355D01*
X-117333Y-16654D01*
X-117008Y-17809D01*
X-116575Y-18675D01*
X-115925Y-19396D01*
X-115059Y-19685D01*
X-114193Y-19396D01*
X-113543Y-18675D01*
X-113110Y-17809D01*
X-112785Y-16654D01*
X-112677Y-15355D01*
X-112785Y-14055D01*
X-113110Y-12900D01*
X-113543Y-12034D01*
X-114193Y-11313D01*
X-115059Y-11024D01*
G01X-106398Y-19974D02*
X-106615Y-19829D01*
Y-19541D01*
X-106398Y-19396D01*
X-106181Y-19541D01*
Y-19829D01*
X-106398Y-19974D01*
G01X-97737Y-11024D02*
X-98603Y-11313D01*
X-99253Y-12034D01*
X-99686Y-12900D01*
X-100011Y-14055D01*
X-100119Y-15355D01*
X-100011Y-16654D01*
X-99686Y-17809D01*
X-99253Y-18675D01*
X-98603Y-19396D01*
X-97737Y-19685D01*
X-96871Y-19396D01*
X-96221Y-18675D01*
X-95788Y-17809D01*
X-95463Y-16654D01*
X-95355Y-15355D01*
X-95463Y-14055D01*
X-95788Y-12900D01*
X-96221Y-12034D01*
X-96871Y-11313D01*
X-97737Y-11024D01*
G01X-89076D02*
X-89942Y-11313D01*
X-90592Y-12034D01*
X-91025Y-12900D01*
X-91350Y-14055D01*
X-91458Y-15355D01*
X-91350Y-16654D01*
X-91025Y-17809D01*
X-90592Y-18675D01*
X-89942Y-19396D01*
X-89076Y-19685D01*
X-88210Y-19396D01*
X-87560Y-18675D01*
X-87127Y-17809D01*
X-86802Y-16654D01*
X-86694Y-15355D01*
X-86802Y-14055D01*
X-87127Y-12900D01*
X-87560Y-12034D01*
X-88210Y-11313D01*
X-89076Y-11024D01*
G01X-117441Y1614D02*
X-116791Y892D01*
X-116033Y459D01*
X-115059Y315D01*
X-114085Y604D01*
X-113327Y1181D01*
X-112785Y2191D01*
X-112677Y3346D01*
X-112894Y4501D01*
X-113435Y5223D01*
X-114193Y5800D01*
X-114951Y5945D01*
X-115709Y5800D01*
X-116683Y5223D01*
X-116358Y8976D01*
X-113435D01*
G01X-106398Y26D02*
X-106615Y171D01*
Y459D01*
X-106398Y604D01*
X-106181Y459D01*
Y171D01*
X-106398Y26D01*
G01X-97737Y8976D02*
X-98603Y8687D01*
X-99253Y7966D01*
X-99686Y7100D01*
X-100011Y5945D01*
X-100119Y4645D01*
X-100011Y3346D01*
X-99686Y2191D01*
X-99253Y1325D01*
X-98603Y604D01*
X-97737Y315D01*
X-96871Y604D01*
X-96221Y1325D01*
X-95788Y2191D01*
X-95463Y3346D01*
X-95355Y4645D01*
X-95463Y5945D01*
X-95788Y7100D01*
X-96221Y7966D01*
X-96871Y8687D01*
X-97737Y8976D01*
G01X-89076D02*
X-89942Y8687D01*
X-90592Y7966D01*
X-91025Y7100D01*
X-91350Y5945D01*
X-91458Y4645D01*
X-91350Y3346D01*
X-91025Y2191D01*
X-90592Y1325D01*
X-89942Y604D01*
X-89076Y315D01*
X-88210Y604D01*
X-87560Y1325D01*
X-87127Y2191D01*
X-86802Y3346D01*
X-86694Y4645D01*
X-86802Y5945D01*
X-87127Y7100D01*
X-87560Y7966D01*
X-88210Y8687D01*
X-89076Y8976D01*
G01X-133059Y468315D02*
Y476976D01*
X-134358Y475244D01*
G01Y468315D02*
X-131760D01*
G01X-126455Y475533D02*
X-125805Y476398D01*
X-125048Y476832D01*
X-124181Y476976D01*
X-123099Y476687D01*
X-122341Y475966D01*
X-122124Y475100D01*
X-122233Y474233D01*
X-122666Y473512D01*
X-124831Y472068D01*
X-125805Y471058D01*
X-126455Y469614D01*
X-126672Y468315D01*
X-122124D01*
G01X-118119Y469614D02*
X-117469Y468892D01*
X-116711Y468459D01*
X-115737Y468315D01*
X-114763Y468604D01*
X-114005Y469181D01*
X-113463Y470191D01*
X-113355Y471346D01*
X-113572Y472501D01*
X-114113Y473223D01*
X-114871Y473800D01*
X-115629Y473945D01*
X-116387Y473800D01*
X-117361Y473223D01*
X-117036Y476976D01*
X-114113D01*
G01X-107076Y468026D02*
X-107293Y468171D01*
Y468459D01*
X-107076Y468604D01*
X-106859Y468459D01*
Y468171D01*
X-107076Y468026D01*
G01X-98415Y476976D02*
X-99281Y476687D01*
X-99931Y475966D01*
X-100364Y475100D01*
X-100689Y473945D01*
X-100797Y472645D01*
X-100689Y471346D01*
X-100364Y470191D01*
X-99931Y469325D01*
X-99281Y468604D01*
X-98415Y468315D01*
X-97549Y468604D01*
X-96899Y469325D01*
X-96466Y470191D01*
X-96141Y471346D01*
X-96033Y472645D01*
X-96141Y473945D01*
X-96466Y475100D01*
X-96899Y475966D01*
X-97549Y476687D01*
X-98415Y476976D01*
G01X-89754D02*
X-90620Y476687D01*
X-91270Y475966D01*
X-91703Y475100D01*
X-92028Y473945D01*
X-92136Y472645D01*
X-92028Y471346D01*
X-91703Y470191D01*
X-91270Y469325D01*
X-90620Y468604D01*
X-89754Y468315D01*
X-88888Y468604D01*
X-88238Y469325D01*
X-87805Y470191D01*
X-87480Y471346D01*
X-87372Y472645D01*
X-87480Y473945D01*
X-87805Y475100D01*
X-88238Y475966D01*
X-88888Y476687D01*
X-89754Y476976D01*
G01X-133059Y478315D02*
Y486976D01*
X-134358Y485244D01*
G01Y478315D02*
X-131760D01*
G01X-126455Y485533D02*
X-125805Y486398D01*
X-125048Y486832D01*
X-124181Y486976D01*
X-123099Y486687D01*
X-122341Y485966D01*
X-122124Y485100D01*
X-122233Y484233D01*
X-122666Y483512D01*
X-124831Y482068D01*
X-125805Y481058D01*
X-126455Y479614D01*
X-126672Y478315D01*
X-122124D01*
G01X-115954D02*
X-115737Y480191D01*
X-115412Y481779D01*
X-114979Y483223D01*
X-114438Y484811D01*
X-113572Y486976D01*
X-117902D01*
G01X-107076Y478026D02*
X-107293Y478171D01*
Y478459D01*
X-107076Y478604D01*
X-106859Y478459D01*
Y478171D01*
X-107076Y478026D01*
G01X-98415Y486976D02*
X-99281Y486687D01*
X-99931Y485966D01*
X-100364Y485100D01*
X-100689Y483945D01*
X-100797Y482645D01*
X-100689Y481346D01*
X-100364Y480191D01*
X-99931Y479325D01*
X-99281Y478604D01*
X-98415Y478315D01*
X-97549Y478604D01*
X-96899Y479325D01*
X-96466Y480191D01*
X-96141Y481346D01*
X-96033Y482645D01*
X-96141Y483945D01*
X-96466Y485100D01*
X-96899Y485966D01*
X-97549Y486687D01*
X-98415Y486976D01*
G01X-89754D02*
X-90620Y486687D01*
X-91270Y485966D01*
X-91703Y485100D01*
X-92028Y483945D01*
X-92136Y482645D01*
X-92028Y481346D01*
X-91703Y480191D01*
X-91270Y479325D01*
X-90620Y478604D01*
X-89754Y478315D01*
X-88888Y478604D01*
X-88238Y479325D01*
X-87805Y480191D01*
X-87480Y481346D01*
X-87372Y482645D01*
X-87480Y483945D01*
X-87805Y485100D01*
X-88238Y485966D01*
X-88888Y486687D01*
X-89754Y486976D01*
G01X-135116Y957533D02*
X-134466Y958398D01*
X-133709Y958832D01*
X-132842Y958976D01*
X-131760Y958687D01*
X-131002Y957966D01*
X-130785Y957100D01*
X-130894Y956233D01*
X-131327Y955512D01*
X-133492Y954068D01*
X-134466Y953058D01*
X-135116Y951614D01*
X-135333Y950315D01*
X-130785D01*
G01X-123099D02*
Y958976D01*
X-127105Y952769D01*
X-121691D01*
G01X-115954Y950315D02*
X-115737Y952191D01*
X-115412Y953779D01*
X-114979Y955223D01*
X-114438Y956811D01*
X-113572Y958976D01*
X-117902D01*
G01X-107076Y950026D02*
X-107293Y950171D01*
Y950459D01*
X-107076Y950604D01*
X-106859Y950459D01*
Y950171D01*
X-107076Y950026D01*
G01X-98415Y958976D02*
X-99281Y958687D01*
X-99931Y957966D01*
X-100364Y957100D01*
X-100689Y955945D01*
X-100797Y954645D01*
X-100689Y953346D01*
X-100364Y952191D01*
X-99931Y951325D01*
X-99281Y950604D01*
X-98415Y950315D01*
X-97549Y950604D01*
X-96899Y951325D01*
X-96466Y952191D01*
X-96141Y953346D01*
X-96033Y954645D01*
X-96141Y955945D01*
X-96466Y957100D01*
X-96899Y957966D01*
X-97549Y958687D01*
X-98415Y958976D01*
G01X-89754D02*
X-90620Y958687D01*
X-91270Y957966D01*
X-91703Y957100D01*
X-92028Y955945D01*
X-92136Y954645D01*
X-92028Y953346D01*
X-91703Y952191D01*
X-91270Y951325D01*
X-90620Y950604D01*
X-89754Y950315D01*
X-88888Y950604D01*
X-88238Y951325D01*
X-87805Y952191D01*
X-87480Y953346D01*
X-87372Y954645D01*
X-87480Y955945D01*
X-87805Y957100D01*
X-88238Y957966D01*
X-88888Y958687D01*
X-89754Y958976D01*
G01X-135116Y977533D02*
X-134466Y978398D01*
X-133709Y978832D01*
X-132842Y978976D01*
X-131760Y978687D01*
X-131002Y977966D01*
X-130785Y977100D01*
X-130894Y976233D01*
X-131327Y975512D01*
X-133492Y974068D01*
X-134466Y973058D01*
X-135116Y971614D01*
X-135333Y970315D01*
X-130785D01*
G01X-126780Y971614D02*
X-126130Y970892D01*
X-125372Y970459D01*
X-124398Y970315D01*
X-123424Y970604D01*
X-122666Y971181D01*
X-122124Y972191D01*
X-122016Y973346D01*
X-122233Y974501D01*
X-122774Y975223D01*
X-123532Y975800D01*
X-124290Y975945D01*
X-125048Y975800D01*
X-126022Y975223D01*
X-125697Y978976D01*
X-122774D01*
G01X-117794Y977533D02*
X-117144Y978398D01*
X-116387Y978832D01*
X-115520Y978976D01*
X-114438Y978687D01*
X-113680Y977966D01*
X-113463Y977100D01*
X-113572Y976233D01*
X-114005Y975512D01*
X-116170Y974068D01*
X-117144Y973058D01*
X-117794Y971614D01*
X-118011Y970315D01*
X-113463D01*
G01X-107076Y970026D02*
X-107293Y970171D01*
Y970459D01*
X-107076Y970604D01*
X-106859Y970459D01*
Y970171D01*
X-107076Y970026D01*
G01X-98415Y978976D02*
X-99281Y978687D01*
X-99931Y977966D01*
X-100364Y977100D01*
X-100689Y975945D01*
X-100797Y974645D01*
X-100689Y973346D01*
X-100364Y972191D01*
X-99931Y971325D01*
X-99281Y970604D01*
X-98415Y970315D01*
X-97549Y970604D01*
X-96899Y971325D01*
X-96466Y972191D01*
X-96141Y973346D01*
X-96033Y974645D01*
X-96141Y975945D01*
X-96466Y977100D01*
X-96899Y977966D01*
X-97549Y978687D01*
X-98415Y978976D01*
G01X-89754D02*
X-90620Y978687D01*
X-91270Y977966D01*
X-91703Y977100D01*
X-92028Y975945D01*
X-92136Y974645D01*
X-92028Y973346D01*
X-91703Y972191D01*
X-91270Y971325D01*
X-90620Y970604D01*
X-89754Y970315D01*
X-88888Y970604D01*
X-88238Y971325D01*
X-87805Y972191D01*
X-87480Y973346D01*
X-87372Y974645D01*
X-87480Y975945D01*
X-87805Y977100D01*
X-88238Y977966D01*
X-88888Y978687D01*
X-89754Y978976D01*
G01X-115742Y1385233D02*
Y1400833D01*
X-118082Y1397713D01*
G01Y1385233D02*
X-113402D01*
G01X-83307Y-19685D02*
X-43307D01*
G01X0Y0D02*
X-83307D01*
G01Y472441D02*
X-7874D01*
G01X0Y480315D02*
X-83307D01*
G01Y952756D02*
X-43307D01*
G01X-43308Y972441D02*
X-83308D01*
G01X-9864Y-777373D02*
Y-796310D01*
G01X85820Y-19685D02*
X-29308D01*
G01X-43308Y-5685D02*
G03X-29308Y-19685I14000J0D01*
G01X0Y3937D02*
Y106969D01*
G01Y3937D02*
Y106969D01*
G01X636457Y0D02*
X3937D01*
G01X636457D02*
X3937D01*
G01X0Y3937D02*
G03X3937Y0I3937J0D01*
G01X0Y3937D02*
G03X3937Y0I3937J0D01*
G01X-43308Y-5685D02*
Y103032D01*
G01X-19331Y15748D02*
G03X-27913I-4291J0D01*
G01D02*
G03X-19331I4291J0D01*
G01X-7874Y50259D02*
Y3937D01*
G01D02*
G03X3937Y-7874I11811J0D01*
G01D02*
X77283D01*
G01X0Y3937D02*
Y106969D01*
G01X636457Y0D02*
X3937D01*
G01X0Y3937D02*
G03X3937Y0I3937J0D01*
G01X-7874Y103032D02*
Y75456D01*
G01Y75460D02*
G03X0I3937J0D01*
G01Y50259D02*
G03X-7874I-3937J0D01*
G01X-43307Y286142D02*
Y116811D01*
G01D02*
X-37402Y110906D01*
G01X-41339Y114843D02*
X-37402Y110906D01*
G01D02*
X-3937D01*
G01X-37402D02*
X-3937D01*
G01X0Y106969D02*
G03X-3937Y110906I-3937J0D01*
G01X0Y106969D02*
G03X-3937Y110906I-3937J0D01*
G01X-43308Y103032D02*
X-7874D01*
G01X-43307Y286142D02*
Y116811D01*
G01X-37402Y292047D02*
Y110906D01*
G01X-12598Y114803D02*
Y152047D01*
G01Y154803D02*
Y192047D01*
G01X-43307Y116811D02*
X-37402Y110906D01*
G01D02*
X-3937D01*
G01X-37402Y114803D02*
X-12598D01*
G01Y152047D02*
X-37402D01*
G01Y154803D02*
X-12598D01*
G01X0Y106969D02*
G03X-3937Y110906I-3937J0D01*
G01X-12598Y194803D02*
Y232047D01*
G01Y192047D02*
X-37402D01*
G01Y194803D02*
X-12598D01*
G01Y234803D02*
Y272047D01*
G01Y232047D02*
X-37402D01*
G01Y234803D02*
X-12598D01*
G01Y272047D02*
X-37402D01*
G01X-43307Y360039D02*
Y300709D01*
G01X-37402Y292047D02*
X-41339Y288110D01*
G01X-37402Y292047D02*
X-43307Y286142D01*
G01Y300709D02*
X-37402Y294803D01*
G01X-41339Y298740D02*
X-37402Y294803D01*
G01X-12598Y292047D02*
X-37402D01*
G01D02*
X-1378D01*
G01X-12598D02*
X-1378D01*
G01X-37402Y294803D02*
X-1378D01*
G01X-37402D02*
X-1378D01*
G01Y292047D02*
G03Y294803I0J1378D01*
G01Y292047D02*
G03Y294803I0J1378D01*
G01X-43307Y360039D02*
Y300709D01*
G01X-37402Y365945D02*
Y294803D01*
G01X-17717Y300630D02*
Y303780D01*
G01Y305630D02*
Y308780D01*
G01Y310630D02*
Y313780D01*
G01Y315630D02*
Y318780D01*
G01Y320630D02*
Y323780D01*
G01Y325630D02*
Y328780D01*
G01Y330630D02*
Y333780D01*
G01X-12598Y274803D02*
Y292047D01*
G01X-37402D02*
X-43307Y286142D01*
G01Y300709D02*
X-37402Y294803D01*
G01Y274803D02*
X-12598D01*
G01X-37402Y292047D02*
X-1378D01*
G01X-37402Y294803D02*
X-1378D01*
G01X-37402Y300630D02*
X-17717D01*
G01Y303780D02*
X-37402D01*
G01Y305630D02*
X-17717D01*
G01Y308780D02*
X-37402D01*
G01Y310630D02*
X-17717D01*
G01Y313780D02*
X-37402D01*
G01Y315630D02*
X-17717D01*
G01Y318780D02*
X-37402D01*
G01Y320630D02*
X-17717D01*
G01Y323780D02*
X-37402D01*
G01Y325630D02*
X-17717D01*
G01Y328780D02*
X-37402D01*
G01Y330630D02*
X-17717D01*
G01X-1378Y292047D02*
G03Y294803I0J1378D01*
G01X-37402Y365945D02*
X-41339Y362008D01*
G01X-37402Y365945D02*
X-43307Y360039D01*
G01X0Y369882D02*
Y468504D01*
G01Y369882D02*
Y468504D01*
G01X-3937Y365945D02*
X-37402D01*
G01X-3937D02*
X-37402D01*
G01X-3937D02*
G03X0Y369882I0J3937D01*
G01X-3937Y365945D02*
G03X0Y369882I0J3937D01*
G01X-7874Y401397D02*
Y373819D01*
G01D02*
X-43307D01*
G01D02*
X-43308Y373820D01*
G01D02*
Y583347D01*
G01X-37402Y365945D02*
X-43307Y360039D01*
G01X-17717Y335630D02*
Y338780D01*
G01Y340630D02*
Y343780D01*
G01Y345630D02*
Y348780D01*
G01Y350630D02*
Y353780D01*
G01Y355630D02*
Y358780D01*
G01X0Y369882D02*
Y468504D01*
G01X-17717Y333780D02*
X-37402D01*
G01Y335630D02*
X-17717D01*
G01Y338780D02*
X-37402D01*
G01Y340630D02*
X-17717D01*
G01Y343780D02*
X-37402D01*
G01Y345630D02*
X-17717D01*
G01Y348780D02*
X-37402D01*
G01Y350630D02*
X-17717D01*
G01Y353780D02*
X-37402D01*
G01Y355630D02*
X-17717D01*
G01Y358780D02*
X-37402D01*
G01X-3937Y365945D02*
X-37402D01*
G01X-3937D02*
G03X0Y369882I0J3937D01*
G01Y401397D02*
G03X-7874I-3937J0D01*
G01Y426594D02*
G03X0I3937J0D01*
G01X-7874D02*
Y530574D01*
G01X3937Y472441D02*
X636457D01*
G01X3937D02*
X636457D01*
G01X3937D02*
G03X0Y468504I0J-3937D01*
G01X3937Y472441D02*
G03X0Y468504I0J-3937D01*
G01Y484252D02*
Y587283D01*
G01Y484252D02*
Y587283D01*
G01X636457Y480315D02*
X3937D01*
G01X636457D02*
X3937D01*
G01X0Y484252D02*
G03X3937Y480315I3937J0D01*
G01X0Y484252D02*
G03X3937Y480315I3937J0D01*
G01X-7874Y472441D02*
X0D01*
G01X3937D02*
X636457D01*
G01X3937D02*
G03X0Y468504I0J-3937D01*
G01X-7874Y583347D02*
Y555771D01*
G01D02*
G03X0I3937J0D01*
G01Y530574D02*
G03X-7874I-3937J0D01*
G01X-43307Y766457D02*
Y597126D01*
G01D02*
X-37402Y591220D01*
G01X-41339Y595157D02*
X-37402Y591220D01*
G01D02*
X-3937D01*
G01X-37402D02*
X-3937D01*
G01X0Y587283D02*
G03X-3937Y591220I-3937J0D01*
G01X0Y587283D02*
G03X-3937Y591220I-3937J0D01*
G01X-43308Y583347D02*
X-7874D01*
G01X-43307Y840354D02*
Y781024D01*
G01X-37402Y772362D02*
X-41339Y768425D01*
G01X-37402Y772362D02*
X-43307Y766457D01*
G01Y781024D02*
X-37402Y775118D01*
G01X-41339Y779055D02*
X-37402Y775118D01*
G01X-12598Y772362D02*
X-37402D01*
G01D02*
X-1378D01*
G01X-12598D02*
X-1378D01*
G01X-37402Y775118D02*
X-1378D01*
G01X-37402D02*
X-1378D01*
G01Y772362D02*
G03Y775118I0J1378D01*
G01Y772362D02*
G03Y775118I0J1378D01*
G01X-37402Y846260D02*
X-41339Y842323D01*
G01X-37402Y846260D02*
X-43307Y840354D01*
G01X0Y850197D02*
Y948819D01*
G01Y850197D02*
Y948819D01*
G01X-3937Y846260D02*
X-37402D01*
G01X-3937D02*
X-37402D01*
G01X-3937D02*
G03X0Y850197I0J3937D01*
G01X-3937Y846260D02*
G03X0Y850197I0J3937D01*
G01X-7874Y881712D02*
Y854134D01*
G01D02*
X-43308D01*
G01D02*
Y958441D01*
G01X0Y881711D02*
G03X-7874I-3937J0D01*
G01X3937Y952756D02*
X636457D01*
G01X3937D02*
X636457D01*
G01X3937D02*
G03X0Y948819I0J-3937D01*
G01X3937Y952756D02*
G03X0Y948819I0J-3937D01*
G01X-29308Y972441D02*
G03X-43308Y958441I0J-14000D01*
G01X-19331Y937008D02*
G03X-27913I-4291J0D01*
G01D02*
G03X-19331I4291J0D01*
G01X0Y952756D02*
X-43307D01*
G01X-7874Y906909D02*
G03X0I3937J0D01*
G01X-7874D02*
Y948819D01*
G01X3937Y960630D02*
G03X-7874Y948819I0J-11811D01*
G01X-29308Y972441D02*
X1317968D01*
G01X-43308Y1000315D02*
Y972441D01*
G01X3937Y960630D02*
X77283D01*
G01X-49968Y1005563D02*
X-49679Y1004697D01*
X-48958Y1004047D01*
X-48092Y1003614D01*
X-46937Y1003289D01*
X-45637Y1003181D01*
X-44338Y1003289D01*
X-43183Y1003614D01*
X-42317Y1004047D01*
X-41596Y1004697D01*
X-41307Y1005563D01*
X-41596Y1006429D01*
X-42317Y1007079D01*
X-43183Y1007512D01*
X-44338Y1007837D01*
X-45637Y1007945D01*
X-46937Y1007837D01*
X-48092Y1007512D01*
X-48958Y1007079D01*
X-49679Y1006429D01*
X-49968Y1005563D01*
G01X-41018Y1014224D02*
X-41163Y1014007D01*
X-41451D01*
X-41596Y1014224D01*
X-41451Y1014441D01*
X-41163D01*
X-41018Y1014224D01*
G01X-49968Y1022885D02*
X-49679Y1022019D01*
X-48958Y1021369D01*
X-48092Y1020936D01*
X-46937Y1020611D01*
X-45637Y1020503D01*
X-44338Y1020611D01*
X-43183Y1020936D01*
X-42317Y1021369D01*
X-41596Y1022019D01*
X-41307Y1022885D01*
X-41596Y1023751D01*
X-42317Y1024401D01*
X-43183Y1024834D01*
X-44338Y1025159D01*
X-45637Y1025267D01*
X-46937Y1025159D01*
X-48092Y1024834D01*
X-48958Y1024401D01*
X-49679Y1023751D01*
X-49968Y1022885D01*
G01Y1031546D02*
X-49679Y1030680D01*
X-48958Y1030030D01*
X-48092Y1029597D01*
X-46937Y1029272D01*
X-45637Y1029164D01*
X-44338Y1029272D01*
X-43183Y1029597D01*
X-42317Y1030030D01*
X-41596Y1030680D01*
X-41307Y1031546D01*
X-41596Y1032412D01*
X-42317Y1033062D01*
X-43183Y1033495D01*
X-44338Y1033820D01*
X-45637Y1033928D01*
X-46937Y1033820D01*
X-48092Y1033495D01*
X-48958Y1033062D01*
X-49679Y1032412D01*
X-49968Y1031546D01*
G01X-9864Y1400383D02*
Y1381446D01*
G01X47460Y-605782D02*
X48110Y-604917D01*
X48867Y-604483D01*
X49734Y-604339D01*
X50816Y-604628D01*
X51574Y-605349D01*
X51791Y-606215D01*
X51682Y-607082D01*
X51249Y-607803D01*
X49084Y-609247D01*
X48110Y-610257D01*
X47460Y-611701D01*
X47243Y-613000D01*
X51791D01*
G01X58178Y-604339D02*
X57312Y-604628D01*
X56662Y-605349D01*
X56229Y-606215D01*
X55904Y-607370D01*
X55796Y-608670D01*
X55904Y-609969D01*
X56229Y-611124D01*
X56662Y-611990D01*
X57312Y-612711D01*
X58178Y-613000D01*
X59044Y-612711D01*
X59694Y-611990D01*
X60127Y-611124D01*
X60452Y-609969D01*
X60560Y-608670D01*
X60452Y-607370D01*
X60127Y-606215D01*
X59694Y-605349D01*
X59044Y-604628D01*
X58178Y-604339D01*
G01X66839Y-613289D02*
X66622Y-613144D01*
Y-612856D01*
X66839Y-612711D01*
X67056Y-612856D01*
Y-613144D01*
X66839Y-613289D01*
G01X75500Y-604339D02*
X74634Y-604628D01*
X73984Y-605349D01*
X73551Y-606215D01*
X73226Y-607370D01*
X73118Y-608670D01*
X73226Y-609969D01*
X73551Y-611124D01*
X73984Y-611990D01*
X74634Y-612711D01*
X75500Y-613000D01*
X76366Y-612711D01*
X77016Y-611990D01*
X77449Y-611124D01*
X77774Y-609969D01*
X77882Y-608670D01*
X77774Y-607370D01*
X77449Y-606215D01*
X77016Y-605349D01*
X76366Y-604628D01*
X75500Y-604339D01*
G01X82970Y-610113D02*
X85568D01*
G01X84161Y-608236D02*
Y-611990D01*
G01X90873Y-613289D02*
X94771Y-604339D01*
G01X100076Y-610113D02*
X102890D01*
G01X37146Y61024D02*
G03I-6988J0D01*
G01X17244Y226378D02*
Y246063D01*
G01X29055D02*
Y226378D01*
G01X25118Y222441D02*
X21181D01*
G01Y250000D02*
X25118D01*
G01X17244Y226378D02*
G03X21181Y222441I3937J0D01*
G01X25118D02*
G03X29055Y226378I0J3937D01*
G01Y246063D02*
G03X25118Y250000I-3937J0D01*
G01X21181D02*
G03X17244Y246063I0J-3937D01*
G01Y226378D02*
Y246063D01*
G01X29055D02*
Y226378D01*
G01X25118Y222441D02*
X21181D01*
G01Y250000D02*
X25118D01*
G01X17244Y226378D02*
G03X21181Y222441I3937J0D01*
G01X25118D02*
G03X29055Y226378I0J3937D01*
G01Y246063D02*
G03X25118Y250000I-3937J0D01*
G01X21181D02*
G03X17244Y246063I0J-3937D01*
G01X37146Y415354D02*
G03I-6988J0D01*
G01Y541339D02*
G03X23169Y541338I-6989J0D01*
G03X37146Y541339I6988J1D01*
G01X17244Y706693D02*
Y726378D01*
G01X29055D02*
Y706693D01*
G01X25118Y702756D02*
X21181D01*
G01Y730315D02*
X25118D01*
G01X17244Y706693D02*
G03X21181Y702756I3937J0D01*
G01X25118D02*
G03X29055Y706693I0J3937D01*
G01Y726378D02*
G03X25118Y730315I-3937J0D01*
G01X21181D02*
G03X17244Y726378I0J-3937D01*
G01X37146Y895669D02*
G03X23169Y895670I-6989J0D01*
G03X37146Y895669I6988J-1D01*
G01X98329Y-779523D02*
X99499Y-777963D01*
X100864Y-777183D01*
X102424Y-776923D01*
X104374Y-777443D01*
X105739Y-778743D01*
X106129Y-780303D01*
X105934Y-781863D01*
X105154Y-783163D01*
X101254Y-785763D01*
X99499Y-787583D01*
X98329Y-790183D01*
X97939Y-792523D01*
X106129D01*
G01X99595Y-622414D02*
G03X108899Y-639683I63744J23202D01*
G01X107474Y-612201D02*
X108124Y-612923D01*
X108882Y-613356D01*
X109856Y-613500D01*
X110830Y-613211D01*
X111588Y-612634D01*
X112130Y-611624D01*
X112238Y-610469D01*
X112021Y-609314D01*
X111480Y-608592D01*
X110722Y-608015D01*
X109964Y-607870D01*
X109206Y-608015D01*
X108232Y-608592D01*
X108557Y-604839D01*
X111480D01*
G01X118517Y-613789D02*
X118300Y-613644D01*
Y-613356D01*
X118517Y-613211D01*
X118734Y-613356D01*
Y-613644D01*
X118517Y-613789D01*
G01X127178Y-604839D02*
X126312Y-605128D01*
X125662Y-605849D01*
X125229Y-606715D01*
X124904Y-607870D01*
X124796Y-609170D01*
X124904Y-610469D01*
X125229Y-611624D01*
X125662Y-612490D01*
X126312Y-613211D01*
X127178Y-613500D01*
X128044Y-613211D01*
X128694Y-612490D01*
X129127Y-611624D01*
X129452Y-610469D01*
X129560Y-609170D01*
X129452Y-607870D01*
X129127Y-606715D01*
X128694Y-605849D01*
X128044Y-605128D01*
X127178Y-604839D01*
G01X137788D02*
Y-613500D01*
G01Y-612201D02*
X137355Y-612923D01*
X136705Y-613356D01*
X135947Y-613500D01*
X135081Y-613211D01*
X134432Y-612490D01*
X133998Y-611624D01*
X133890Y-610613D01*
X133998Y-609603D01*
X134432Y-608736D01*
X135081Y-608015D01*
X135947Y-607726D01*
X136705Y-607870D01*
X137246Y-608159D01*
X137788Y-608736D01*
G01X142876Y-609603D02*
X146341D01*
X146016Y-608592D01*
X145474Y-608015D01*
X144717Y-607726D01*
X143959Y-607870D01*
X143309Y-608303D01*
X142876Y-609314D01*
X142659Y-610180D01*
Y-611046D01*
X142876Y-611912D01*
X143417Y-612778D01*
X144067Y-613356D01*
X144825Y-613500D01*
X145583Y-613211D01*
X146341Y-612345D01*
G01X151645Y-615665D02*
X152403Y-616243D01*
X153269Y-616387D01*
X154027Y-616243D01*
X154677Y-615521D01*
X155110Y-614510D01*
Y-607726D01*
G01Y-608881D02*
X154677Y-608303D01*
X154027Y-607870D01*
X153269Y-607726D01*
X152403Y-608015D01*
X151862Y-608592D01*
X151429Y-609603D01*
X151212Y-610613D01*
X151320Y-611479D01*
X151754Y-612490D01*
X152403Y-613211D01*
X153269Y-613500D01*
X153919Y-613356D01*
X154677Y-612778D01*
X155110Y-612201D01*
G01X160306Y-613500D02*
Y-607726D01*
G01Y-608881D02*
X160848Y-608303D01*
X161389Y-607870D01*
X162147Y-607726D01*
X162688Y-607870D01*
X163338Y-608303D01*
G01X168859Y-609603D02*
X172324D01*
X171999Y-608592D01*
X171457Y-608015D01*
X170700Y-607726D01*
X169942Y-607870D01*
X169292Y-608303D01*
X168859Y-609314D01*
X168642Y-610180D01*
Y-611046D01*
X168859Y-611912D01*
X169400Y-612778D01*
X170050Y-613356D01*
X170808Y-613500D01*
X171566Y-613211D01*
X172324Y-612345D01*
G01X177520Y-609603D02*
X180985D01*
X180660Y-608592D01*
X180118Y-608015D01*
X179361Y-607726D01*
X178603Y-607870D01*
X177953Y-608303D01*
X177520Y-609314D01*
X177303Y-610180D01*
Y-611046D01*
X177520Y-611912D01*
X178061Y-612778D01*
X178711Y-613356D01*
X179469Y-613500D01*
X180227Y-613211D01*
X180985Y-612345D01*
G01X159402Y-599213D02*
X91567D01*
G01X114213Y-617093D02*
X95896Y-623760D01*
G01X98340Y-579803D02*
G03X95504Y-599213I65000J-19409D01*
G01X93694Y-19685D02*
X1317968D01*
G01X93694D02*
G03X85820I-3937J0D01*
G01X89265D02*
X90249D01*
G01X89757D02*
Y-19291D01*
G01Y-19685D02*
Y-20079D01*
G01X107993Y-7874D02*
X304843D01*
G01X107993Y0D02*
G03Y-7874I0J-3937D01*
G01X77283D02*
G03Y0I0J3937D01*
G01X107993Y480315D02*
G03Y472441I0J-3937D01*
G01X77283D02*
G03Y480315I0J3937D01*
G01X107993Y960630D02*
G03Y952756I0J-3937D01*
G01X77283D02*
G03Y960630I0J3937D01*
G01X107993D02*
X304843D01*
G01X98329Y1398233D02*
X99499Y1399793D01*
X100864Y1400573D01*
X102424Y1400833D01*
X104374Y1400313D01*
X105739Y1399013D01*
X106129Y1397453D01*
X105934Y1395893D01*
X105154Y1394593D01*
X101254Y1391993D01*
X99499Y1390173D01*
X98329Y1387573D01*
X97939Y1385233D01*
X106129D01*
G01X157434Y-601362D02*
Y-603363D01*
G01X163339Y-599213D02*
Y-605512D01*
G01D02*
X157434Y-603363D01*
G01Y-601362D02*
X163339Y-599213D01*
G01Y-605512D02*
X841135D01*
G01X163339Y-599213D02*
X841135D01*
G01X153734Y-602709D02*
X138574Y-608226D01*
G01X157434Y-597425D02*
Y-558039D01*
G01X163339Y-595276D02*
Y-558039D01*
G01X180248Y-560000D02*
Y-551339D01*
X178949Y-553071D01*
G01Y-560000D02*
X181547D01*
G01X188909Y-560289D02*
X188692Y-560144D01*
Y-559856D01*
X188909Y-559711D01*
X189126Y-559856D01*
Y-560144D01*
X188909Y-560289D01*
G01X195188Y-558701D02*
X195838Y-559423D01*
X196596Y-559856D01*
X197570Y-560000D01*
X198544Y-559711D01*
X199302Y-559134D01*
X199844Y-558124D01*
X199952Y-556969D01*
X199735Y-555814D01*
X199194Y-555092D01*
X198436Y-554515D01*
X197678Y-554370D01*
X196920Y-554515D01*
X195946Y-555092D01*
X196271Y-551339D01*
X199194D01*
G01X206231D02*
X205365Y-551628D01*
X204715Y-552349D01*
X204282Y-553215D01*
X203957Y-554370D01*
X203849Y-555670D01*
X203957Y-556969D01*
X204282Y-558124D01*
X204715Y-558990D01*
X205365Y-559711D01*
X206231Y-560000D01*
X207097Y-559711D01*
X207747Y-558990D01*
X208180Y-558124D01*
X208505Y-556969D01*
X208613Y-555670D01*
X208505Y-554370D01*
X208180Y-553215D01*
X207747Y-552349D01*
X207097Y-551628D01*
X206231Y-551339D01*
G01X213701Y-557113D02*
X216299D01*
G01X214892Y-555236D02*
Y-558990D01*
G01X221604Y-560289D02*
X225502Y-551339D01*
G01X230807Y-557113D02*
X233621D01*
G01X157434Y-561976D02*
X137749D01*
G01D02*
X160387D01*
G01X163339D02*
X266761D01*
G01D02*
X160387D01*
G01X121252Y-18285D02*
Y-21085D01*
G01X152747Y-18285D02*
Y-21085D01*
G01X209806Y-777373D02*
Y-796310D01*
G01X196804Y-605512D02*
Y-599213D01*
G01X199363D02*
Y-605512D01*
G01X200741D02*
Y-599213D01*
G01X204678Y-605512D02*
Y-599213D01*
G01X217985Y-605512D02*
Y-599213D01*
G01X221922Y-605512D02*
Y-599213D01*
G01X223910D02*
Y-605512D01*
G01X225859D02*
Y-599213D01*
G01X229796Y-605512D02*
Y-599213D01*
G01X184242Y-18285D02*
Y-21085D01*
G01X215737Y-18285D02*
Y-21085D01*
G01X209806Y1400383D02*
Y1381446D01*
G01X237887Y-599213D02*
Y-605512D01*
G01X238828Y-551150D02*
X237962Y-551439D01*
X237312Y-552160D01*
X236879Y-553026D01*
X236554Y-554181D01*
X236446Y-555481D01*
X236554Y-556780D01*
X236879Y-557935D01*
X237312Y-558801D01*
X237962Y-559522D01*
X238828Y-559811D01*
X239694Y-559522D01*
X240344Y-558801D01*
X240777Y-557935D01*
X241102Y-556780D01*
X241210Y-555481D01*
X241102Y-554181D01*
X240777Y-553026D01*
X240344Y-552160D01*
X239694Y-551439D01*
X238828Y-551150D01*
G01X247489Y-560100D02*
X247272Y-559955D01*
Y-559667D01*
X247489Y-559522D01*
X247706Y-559667D01*
Y-559955D01*
X247489Y-560100D01*
G01X256150Y-559811D02*
Y-551150D01*
X254851Y-552882D01*
G01Y-559811D02*
X257449D01*
G01X262429Y-558512D02*
X263079Y-559234D01*
X263837Y-559667D01*
X264811Y-559811D01*
X265785Y-559522D01*
X266543Y-558945D01*
X267085Y-557935D01*
X267193Y-556780D01*
X266976Y-555625D01*
X266435Y-554903D01*
X265677Y-554326D01*
X264919Y-554181D01*
X264161Y-554326D01*
X263187Y-554903D01*
X263512Y-551150D01*
X266435D01*
G01X270224Y-559811D02*
Y-554037D01*
G01Y-555625D02*
X270549Y-554903D01*
X271090Y-554326D01*
X271848Y-554037D01*
X272606Y-554326D01*
X273147Y-554903D01*
X273472Y-555625D01*
Y-559811D01*
G01Y-555625D02*
X273797Y-554903D01*
X274338Y-554326D01*
X275096Y-554037D01*
X275854Y-554326D01*
X276395Y-554903D01*
X276720Y-555769D01*
Y-559811D01*
G01X278885D02*
Y-554037D01*
G01Y-555625D02*
X279210Y-554903D01*
X279751Y-554326D01*
X280509Y-554037D01*
X281267Y-554326D01*
X281808Y-554903D01*
X282133Y-555625D01*
Y-559811D01*
G01Y-555625D02*
X282458Y-554903D01*
X282999Y-554326D01*
X283757Y-554037D01*
X284515Y-554326D01*
X285056Y-554903D01*
X285381Y-555769D01*
Y-559811D01*
G01X247232Y-18285D02*
Y-21085D01*
G01X278728Y-18285D02*
Y-21085D01*
G01X317412Y-789403D02*
X318582Y-791223D01*
X320142Y-792263D01*
X321897Y-792523D01*
X323457Y-792263D01*
X325017Y-790963D01*
X325992Y-789403D01*
X326187Y-787843D01*
X325797Y-786023D01*
X324432Y-784723D01*
X323067Y-784203D01*
X321312D01*
G01X323067D02*
X324237Y-783423D01*
X325212Y-782123D01*
X325602Y-780563D01*
X325212Y-779003D01*
X324237Y-777703D01*
X322482Y-776923D01*
X320727Y-777183D01*
X318972Y-778223D01*
G01X335552Y-7874D02*
X532402D01*
G01X304843D02*
G03Y0I0J3937D01*
G01X335552D02*
G03Y-7874I0J-3937D01*
G01X315199Y232232D02*
Y212547D01*
G01X309540Y232232D02*
X320858D01*
G01X335552Y480315D02*
G03Y472441I0J-3937D01*
G01X304843D02*
G03Y480315I0J3937D01*
G01X329869Y717702D02*
Y698017D01*
G01X324210Y717702D02*
X335528D01*
G01X304843Y952756D02*
G03Y960630I0J3937D01*
G01X335552D02*
G03Y952756I0J-3937D01*
G01Y960630D02*
X532402D01*
G01X317412Y1388353D02*
X318582Y1386533D01*
X320142Y1385493D01*
X321897Y1385233D01*
X323457Y1385493D01*
X325017Y1386793D01*
X325992Y1388353D01*
X326187Y1389913D01*
X325797Y1391733D01*
X324432Y1393033D01*
X323067Y1393553D01*
X321312D01*
G01X323067D02*
X324237Y1394333D01*
X325212Y1395633D01*
X325602Y1397193D01*
X325212Y1398753D01*
X324237Y1400053D01*
X322482Y1400833D01*
X320727Y1400573D01*
X318972Y1399533D01*
G01X429474Y-777373D02*
Y-796310D01*
G01Y1400383D02*
Y1381446D01*
G01X506535Y23622D02*
G03I-7873J0D01*
G01X526220Y448819D02*
G03I-7873J0D01*
G01X506535Y503937D02*
G03X490788I-7874J0D01*
G03X506535I7873J0D01*
G01X526220Y929134D02*
G03I-7874J0D01*
G01X543711Y-792523D02*
Y-776923D01*
X536496Y-788103D01*
X546246D01*
G01X563111Y-7874D02*
X725552D01*
G01X563111Y0D02*
G03Y-7874I0J-3937D01*
G01X532402D02*
G03Y0I0J3937D01*
G01X640394Y50591D02*
X567559D01*
G01D02*
Y353740D01*
G01X640394Y50591D02*
X567559D01*
G01D02*
Y353740D01*
G01X620709Y120413D02*
X554724D01*
G01X622709Y121909D02*
X573409D01*
G01X568209Y150409D02*
X622709D01*
G01X603609Y154409D02*
X568209D01*
G01Y156909D02*
X603609D01*
G01X609209Y158909D02*
X568209D01*
G01X554724Y120413D02*
Y328406D01*
G01X568209Y127109D02*
Y162909D01*
G01Y127109D02*
G03X573409Y121909I5200J0D01*
G01X620709Y120413D02*
X554724D01*
G01X622709Y121909D02*
X573409D01*
G01X568209Y150409D02*
X622709D01*
G01X603609Y154409D02*
X568209D01*
G01Y156909D02*
X603609D01*
G01X609209Y158909D02*
X568209D01*
G01X554724Y120413D02*
Y328406D01*
G01X568209Y127109D02*
Y162909D01*
G01Y127109D02*
G03X573409Y121909I5200J0D01*
G01X568979Y162909D02*
G03X572439I1730J-1019D01*
G01X568979D02*
G03X572438I1729J-1019D01*
G01X568979D01*
G01X569459Y161059D02*
X571959D01*
G01Y162759D02*
X569459D01*
G01X588709Y162909D02*
X568209D01*
G01Y170909D02*
X588709D01*
G01X569459Y171059D02*
X571959D01*
G01Y172759D02*
X569459D01*
G01X609209Y174909D02*
X568209D01*
G01X609209Y178909D02*
X568209D01*
G01X569459Y181059D02*
X571959D01*
G01Y182759D02*
X569459D01*
G01X588709Y182909D02*
X568209D01*
G01Y190909D02*
X588709D01*
G01X569459Y191059D02*
X571959D01*
G01Y192759D02*
X569459D01*
G01X609209Y194909D02*
X568209D01*
G01Y196909D02*
X603609D01*
G01X568209Y199409D02*
X588709D01*
G01X569409Y203109D02*
X588709D01*
G01X569409Y205709D02*
X588709D01*
G01X569409Y213109D02*
X588709D01*
G01X569409Y215709D02*
X588709D01*
G01X568209Y199409D02*
Y190909D01*
G01Y182909D02*
Y170909D01*
G01X569409Y215709D02*
Y213109D01*
G01Y205709D02*
Y203109D01*
G01X569459Y192759D02*
Y191059D01*
G01Y182759D02*
Y181059D01*
G01Y172759D02*
Y171059D01*
G01Y162759D02*
Y161059D01*
G01X571959D02*
Y162759D01*
G01Y171059D02*
Y172759D01*
G01Y181059D02*
Y182759D01*
G01Y191059D02*
Y192759D01*
G01X572009Y203109D02*
Y205709D01*
G01Y213109D02*
Y215709D01*
G01X568956Y170909D02*
G03X572461I1753J981D01*
G01X572438Y162909D02*
G03X568979I-1729J-1019D01*
G01X568956Y190909D02*
G03X572461I1753J981D01*
G01X572438Y182909D02*
G03X568979I-1729J-1019D01*
G01X572239Y203109D02*
G03Y205710I-1530J1301D01*
G01D02*
G03Y203109I-1530J-1301D01*
G01Y213109D02*
G03Y215710I-1530J1300D01*
G01D02*
G03Y213109I-1530J-1301D01*
G01X569459Y161059D02*
X571959D01*
G01Y162759D02*
X569459D01*
G01X588709Y162909D02*
X568209D01*
G01Y170909D02*
X588709D01*
G01X569459Y171059D02*
X571959D01*
G01Y172759D02*
X569459D01*
G01X609209Y174909D02*
X568209D01*
G01X609209Y178909D02*
X568209D01*
G01X569459Y181059D02*
X571959D01*
G01Y182759D02*
X569459D01*
G01X588709Y182909D02*
X568209D01*
G01Y190909D02*
X588709D01*
G01X569459Y191059D02*
X571959D01*
G01Y192759D02*
X569459D01*
G01X609209Y194909D02*
X568209D01*
G01Y196909D02*
X603609D01*
G01X568209Y199409D02*
X588709D01*
G01X569409Y203109D02*
X588709D01*
G01X569409Y205709D02*
X588709D01*
G01X569409Y213109D02*
X588709D01*
G01X569409Y215709D02*
X588709D01*
G01X568209Y199409D02*
Y190909D01*
G01Y182909D02*
Y170909D01*
G01X569409Y215709D02*
Y213109D01*
G01Y205709D02*
Y203109D01*
G01X569459Y192759D02*
Y191059D01*
G01Y182759D02*
Y181059D01*
G01Y172759D02*
Y171059D01*
G01Y162759D02*
Y161059D01*
G01X571959D02*
Y162759D01*
G01Y171059D02*
Y172759D01*
G01Y181059D02*
Y182759D01*
G01Y191059D02*
Y192759D01*
G01X572009Y203109D02*
Y205709D01*
G01Y213109D02*
Y215709D01*
G01X572461Y170909D02*
G03X568957I-1752J981D01*
G01D02*
G03X572461I1752J981D01*
G01X572439Y162909D02*
G03X568979I-1730J-1019D01*
G01X572239Y203109D02*
G03Y205709I-1530J1300D01*
G01X572461Y190909D02*
G03X568957I-1752J981D01*
G01X568979Y182909D02*
G03X572439I1730J-1019D01*
G01X572239Y205709D02*
G03Y203109I-1530J-1300D01*
G01X568957Y190909D02*
G03X572461I1752J981D01*
G01X572439Y182909D02*
G03X568979I-1730J-1019D01*
G01X572239Y213109D02*
G03Y215709I-1530J1300D01*
G01D02*
G03Y213109I-1530J-1300D01*
G01X572461Y170909D02*
G03X568956I-1753J981D01*
G01X572461D01*
G01Y190909D02*
G03X568956I-1753J981D01*
G01X572461D01*
G01X568979Y182909D02*
G03X572438I1729J-1019D01*
G01X568979D01*
G01X569409Y223109D02*
X588709D01*
G01X569409Y225709D02*
X588709D01*
G01X569409Y233109D02*
X588709D01*
G01X569409Y235709D02*
X588709D01*
G01X569409Y243109D02*
X588709D01*
G01X569409Y245709D02*
X588709D01*
G01Y249409D02*
X568209D01*
G01X603609Y251909D02*
X568209D01*
G01X609209Y253909D02*
X568209D01*
G01X569459Y256059D02*
X571959D01*
G01Y257759D02*
X569459D01*
G01X588709Y257909D02*
X568209D01*
G01Y265909D02*
X588709D01*
G01X569459Y266059D02*
X571959D01*
G01Y267759D02*
X569459D01*
G01X609209Y269909D02*
X568209D01*
G01X609209Y273909D02*
X568209D01*
G01Y277909D02*
Y265909D01*
G01Y257909D02*
Y249409D01*
G01X569409Y245709D02*
Y243109D01*
G01Y235709D02*
Y233109D01*
G01Y225709D02*
Y223109D01*
G01X569459Y267759D02*
Y266059D01*
G01Y257759D02*
Y256059D01*
G01X571959D02*
Y257759D01*
G01Y266059D02*
Y267759D01*
G01X572009Y223109D02*
Y225709D01*
G01Y233109D02*
Y235709D01*
G01Y243109D02*
Y245709D01*
G01X572239Y233109D02*
G03Y235710I-1530J1300D01*
G01Y223109D02*
G03Y225710I-1530J1300D01*
G01Y235710D02*
G03Y233109I-1530J-1301D01*
G01Y225710D02*
G03Y223109I-1530J-1301D01*
G01Y243109D02*
G03Y245710I-1530J1300D01*
G01D02*
G03Y243109I-1530J-1301D01*
G01X568979Y265909D02*
G03X572438I1729J1020D01*
G01X572461Y257909D02*
G03X568956I-1753J-980D01*
G01X569409Y223109D02*
X588709D01*
G01X569409Y225709D02*
X588709D01*
G01X569409Y233109D02*
X588709D01*
G01X569409Y235709D02*
X588709D01*
G01X569409Y243109D02*
X588709D01*
G01X569409Y245709D02*
X588709D01*
G01Y249409D02*
X568209D01*
G01X603609Y251909D02*
X568209D01*
G01X609209Y253909D02*
X568209D01*
G01X569459Y256059D02*
X571959D01*
G01Y257759D02*
X569459D01*
G01X588709Y257909D02*
X568209D01*
G01Y265909D02*
X588709D01*
G01X569459Y266059D02*
X571959D01*
G01Y267759D02*
X569459D01*
G01X609209Y269909D02*
X568209D01*
G01X609209Y273909D02*
X568209D01*
G01Y277909D02*
Y265909D01*
G01Y257909D02*
Y249409D01*
G01X569409Y245709D02*
Y243109D01*
G01Y235709D02*
Y233109D01*
G01Y225709D02*
Y223109D01*
G01X569459Y267759D02*
Y266059D01*
G01Y257759D02*
Y256059D01*
G01X571959D02*
Y257759D01*
G01Y266059D02*
Y267759D01*
G01X572009Y223109D02*
Y225709D01*
G01Y233109D02*
Y235709D01*
G01Y243109D02*
Y245709D01*
G01X572239Y233109D02*
G03Y235709I-1530J1300D01*
G01Y223109D02*
G03Y225709I-1530J1300D01*
G01Y235709D02*
G03Y233109I-1530J-1300D01*
G01Y225709D02*
G03Y223109I-1530J-1300D01*
G01Y243109D02*
G03Y245709I-1530J1300D01*
G01X568957Y257909D02*
G03X572461I1752J-980D01*
G01X572239Y245709D02*
G03Y243109I-1530J-1300D01*
G01X572461Y257909D02*
G03X568957I-1752J-980D01*
G01X572439Y265909D02*
G03X568979I-1730J1020D01*
G01D02*
G03X572439I1730J1020D01*
G01X572438D02*
G03X568979I-1729J1020D01*
G01X572438D01*
G01X568956Y257909D02*
G03X572461I1753J-980D01*
G01X568956D01*
G01X569459Y276059D02*
X571959D01*
G01Y277759D02*
X569459D01*
G01X588709Y277909D02*
X568209D01*
G01Y285909D02*
X588709D01*
G01X569459Y286059D02*
X571959D01*
G01Y287759D02*
X569459D01*
G01X609209Y289909D02*
X568209D01*
G01Y291909D02*
X603609D01*
G01Y294409D02*
X568209D01*
G01X622709Y298409D02*
X568209D01*
G01X622709Y326909D02*
X573409D01*
G01X554724Y328406D02*
X620709D01*
G01X568209Y285909D02*
Y321709D01*
G01X569459Y287759D02*
Y286059D01*
G01Y277759D02*
Y276059D01*
G01X571959D02*
Y277759D01*
G01Y286059D02*
Y287759D01*
G01X572461Y277909D02*
G03X568956I-1753J-980D01*
G01X573409Y326909D02*
G03X568209Y321709I0J-5200D01*
G01X568979Y285909D02*
G03X572438I1729J1020D01*
G01X569459Y276059D02*
X571959D01*
G01Y277759D02*
X569459D01*
G01X588709Y277909D02*
X568209D01*
G01Y285909D02*
X588709D01*
G01X569459Y286059D02*
X571959D01*
G01Y287759D02*
X569459D01*
G01X609209Y289909D02*
X568209D01*
G01Y291909D02*
X603609D01*
G01Y294409D02*
X568209D01*
G01X622709Y298409D02*
X568209D01*
G01X622709Y326909D02*
X573409D01*
G01X554724Y328406D02*
X620709D01*
G01X568209Y285909D02*
Y321709D01*
G01X569459Y287759D02*
Y286059D01*
G01Y277759D02*
Y276059D01*
G01X571959D02*
Y277759D01*
G01Y286059D02*
Y287759D01*
G01X572439Y285909D02*
G03X568979I-1730J1020D01*
G01X568957Y277909D02*
G03X572461I1752J-980D01*
G01X568979Y285909D02*
G03X572439I1730J1020D01*
G01X572461Y277909D02*
G03X568957I-1752J-980D01*
G01X573409Y326909D02*
G03X568209Y321709I0J-5200D01*
G01X568956Y277909D02*
G03X572461I1753J-980D01*
G01X568956D01*
G01X572438Y285909D02*
G03X568979I-1729J1020D01*
G01X572438D01*
G01X627391Y353740D02*
X545906D01*
G01X627391D02*
X545906D01*
G01X627391Y378543D02*
X545906D01*
G01X627391D02*
X545906D01*
G01X541969Y357677D02*
Y374606D01*
G01Y357677D02*
Y374606D01*
G01X567559Y402165D02*
Y378543D01*
G01X545906D02*
G03X541969Y374606I0J-3937D01*
G01Y357677D02*
G03X545906Y353740I3937J0D01*
G01X541969Y357677D02*
G03X545906Y353740I3937J0D01*
G01Y378543D02*
G03X541969Y374606I0J-3937D01*
G01X627391Y353740D02*
X545906D01*
G01X627391Y378543D02*
X545906D01*
G01X541969Y357677D02*
Y374606D01*
G01X567559Y402165D02*
Y378543D01*
G01X541969Y357677D02*
G03X545906Y353740I3937J0D01*
G01Y378543D02*
G03X541969Y374606I0J-3937D01*
G01X567559Y402165D02*
X640394D01*
G01X569724Y431748D02*
X578386Y438740D01*
G01X580748Y436378D02*
X577598Y433071D01*
G01X570541Y428144D02*
X570621Y428160D01*
G01X567260Y441007D02*
X567931Y442851D01*
G01X568628Y437987D02*
X568708Y438003D01*
G01X567559Y402165D02*
X640394D01*
G01X575851Y425135D02*
X575180Y423291D01*
G01X602795Y423031D02*
X559882D01*
G01Y425394D02*
X602795D01*
G01X573661Y425689D02*
X571693D01*
G01X562244Y425787D02*
X602795D01*
G01X559882Y425984D02*
X557323D01*
G01X559882Y426181D02*
X557520D01*
G01X562244D02*
X603189D01*
G01X574252Y426378D02*
X598661D01*
G01X561457Y427165D02*
X559882D01*
G01X569724Y427402D02*
X581142D01*
G01X570457Y428150D02*
X568150D01*
G01X591772Y428740D02*
X575630D01*
G01X559882Y429331D02*
X557520D01*
G01X575433Y429724D02*
X591969D01*
G01X583152Y429789D02*
X575728D01*
G01Y429809D02*
X583168D01*
G01X583110Y429929D02*
X575728D01*
G01X583152Y429985D02*
X575728D01*
G01Y429996D02*
X583168D01*
G01X583110Y430056D02*
X575728D01*
G01X591673Y430422D02*
X575728D01*
G01X575433Y430512D02*
X591969D01*
G01X591673Y430609D02*
X575728D01*
G01X560669Y430709D02*
X563819D01*
G01X575728Y430796D02*
X591673D01*
G01X575630Y430906D02*
X569724D01*
G01X575433Y431299D02*
X590984D01*
G01X583110Y431483D02*
X575728D01*
G01X575433Y431594D02*
X591969D01*
G01X581929Y431687D02*
X576614D01*
G01X583110Y431721D02*
X575728D01*
G01Y431779D02*
X583110D01*
G01Y431791D02*
X575728D01*
G01X581929Y432243D02*
X576614D01*
G01X585276Y432283D02*
X577402D01*
G01X575433D02*
X567559D01*
G01X577402Y432347D02*
X576614D01*
G01X577402Y432382D02*
X576614D01*
G01X577402Y432579D02*
X576614D01*
G01X557520Y432874D02*
X559882D01*
G01X557520Y433268D02*
X559882D01*
G01X577402Y433563D02*
X576614D01*
G01X577402Y433760D02*
X576614D01*
G01X577402Y433794D02*
X576614D01*
G01X585276Y433858D02*
X577402D01*
G01X575433D02*
X567559D01*
G01X581929Y433898D02*
X576614D01*
G01X583110Y434350D02*
X575728D01*
G01X583110Y434363D02*
X575728D01*
G01Y434420D02*
X583110D01*
G01X581929Y434455D02*
X576614D01*
G01X575433Y434547D02*
X591969D01*
G01X583110Y434658D02*
X575728D01*
G01X590984Y434843D02*
X575433D01*
G01X569724Y435236D02*
X575630D01*
G01X591673Y435346D02*
X575728D01*
G01X563819Y435433D02*
X560669D01*
G01X575728Y435533D02*
X591673D01*
G01X575433Y435630D02*
X591969D01*
G01X575728Y435720D02*
X591673D01*
G01X575728Y436086D02*
X583110D01*
G01X583168Y436146D02*
X575728D01*
G01X583152Y436156D02*
X575728D01*
G01Y436213D02*
X583110D01*
G01X583168Y436333D02*
X575728D01*
G01X583152Y436353D02*
X575728D01*
G01X575433Y436417D02*
X591969D01*
G01X575630Y437402D02*
X591772D01*
G01X570541Y428144D02*
X581142Y428100D01*
G01Y428116D02*
X570621Y428160D01*
G01X568150Y437992D02*
X568543D01*
G01X569724Y438740D02*
X571102D01*
G01X576614D02*
X581142D01*
G01X559882Y438976D02*
X561457D01*
G01X574252Y439764D02*
X598661D01*
G01X562244Y439961D02*
X603189D01*
G01X557323Y440157D02*
X559882D01*
G01X562244Y440354D02*
X602795D01*
G01X571693Y440453D02*
X573661D01*
G01X602795Y440748D02*
X559882D01*
G01Y443110D02*
X602795D01*
G01X585856Y437915D02*
X568628Y437987D01*
G01X568708Y438003D02*
X581142Y437950D01*
G01X557323Y425984D02*
Y440157D01*
G01X557520Y432874D02*
Y425984D01*
G01D02*
Y425394D01*
G01Y433268D02*
Y440157D01*
G01D02*
Y440748D01*
G01X559882Y423031D02*
Y425984D01*
G01D02*
Y432874D01*
G01Y433268D02*
Y440157D01*
G01D02*
Y443110D01*
G01X560472Y425394D02*
Y440748D01*
G01X562244Y425787D02*
Y426378D01*
G01Y439764D02*
Y440354D01*
G01X564409Y443110D02*
Y440748D01*
G01Y423031D02*
Y425394D01*
G01X566969Y423031D02*
Y425394D01*
G01Y440748D02*
Y443110D01*
G01X567362Y440354D02*
Y438780D01*
G01Y427362D02*
Y425787D01*
G01X567559Y433858D02*
Y432283D01*
G01X567665Y433858D02*
Y432283D01*
G01X569134Y433858D02*
Y432283D01*
G01X569724Y427402D02*
Y438740D01*
G01X569921Y432283D02*
Y433858D01*
G01X570315D02*
Y432283D01*
G01X571102Y427402D02*
Y426280D01*
G01Y438740D02*
Y439862D01*
G01X572677Y433858D02*
Y432283D01*
G01X573071Y433858D02*
Y432283D01*
G01X573858Y433858D02*
Y432283D01*
G01X574252Y426378D02*
Y426280D01*
G01Y439764D02*
Y439862D01*
G01X575328Y433858D02*
Y432283D01*
G01X575433Y436417D02*
Y429724D01*
G01X575630Y428740D02*
Y430906D01*
G01Y435236D02*
Y437402D01*
G01X575728Y429789D02*
Y436353D01*
G01X576024Y425394D02*
Y423031D01*
G01Y440748D02*
Y443110D01*
G01X576122Y434350D02*
Y434055D01*
G01Y432087D02*
Y431791D01*
G01X576319Y434350D02*
Y434055D01*
G01Y432087D02*
Y431791D01*
G01X576614Y434547D02*
Y433563D01*
G01Y432579D02*
Y431594D01*
G01Y427402D02*
Y426378D01*
G01Y438740D02*
Y439764D01*
G01X577402Y433858D02*
Y432283D01*
G01X577507Y433858D02*
Y432283D01*
G01X567931Y423291D02*
X567260Y425135D01*
G01X568543Y437992D02*
X570457Y428150D01*
G01X570541Y428144D02*
X568628Y437987D01*
G01X570621Y428160D02*
X568708Y438003D01*
G01X577598Y433071D02*
X580748Y429764D01*
G01X575180Y442851D02*
X575851Y441007D01*
G01X568708Y438003D02*
G03X568543Y437992I3814J-58460D01*
G01X570621Y428160D02*
G03X570457Y428150I3484J-58479D01*
G01X570513Y428146D02*
G03X570457Y428150I-1626J-22369D01*
G01X568628Y437987D02*
G03X568543Y437992I-968J-15727D01*
G01X570541Y428144D02*
G03X570513Y428146I-715J-9809D01*
G01X567931Y423291D02*
G03X568301Y423031I370J134D01*
G01X574809D02*
G03X575180Y423291I1J394D01*
G01X557520Y425394D02*
G03X559882Y423031I2362J-1D01*
G01X574261Y428051D02*
G03I-1280J0D01*
G01X568150Y428150D02*
G03X567362Y427362I0J-788D01*
G01X562244Y426378D02*
G03X561457Y427165I-787J0D01*
G01X560669Y430709D02*
G03X559882Y429921I1J-788D01*
G01X573661Y425689D02*
G03X574252Y426280I1J590D01*
G01X571102D02*
G03X571693Y425689I591J0D01*
G01X573474Y428051D02*
G03I-493J0D01*
G01X567260Y425135D02*
G03X566890Y425394I-370J-135D01*
G01X576221D02*
G03X575851Y425135I0J-394D01*
G01X565531Y433071D02*
G03I-2893J0D01*
G01X563819Y430709D02*
G03Y435433I0J2362D01*
G01X564308Y433071D02*
G03I-1670J0D01*
G01X559882Y436220D02*
G03X560669Y435433I787J0D01*
G01X576526Y431692D02*
G03X576614Y431687I92J835D01*
G01X576457Y432333D02*
G03X576426Y432328I112J-794D01*
G01X576614Y432579D02*
G03X576122Y432087I0J-492D01*
G01X576614Y432382D02*
G03X576319Y432087I0J-295D01*
G01X576122Y431594D02*
G03X576319Y431791I0J197D01*
G01X576426Y433814D02*
G03X576457Y433808I168J784D01*
G01X576122Y434055D02*
G03X576614Y433563I492J0D01*
G01X576319Y434055D02*
G03X576614Y433760I295J0D01*
G01X576319Y434350D02*
G03X576122Y434547I-197J0D01*
G01X559882Y443110D02*
G03X557520Y440748I0J-2362D01*
G01X574261Y437894D02*
G03I-1280J0D01*
G01X561457Y438976D02*
G03X562244Y439764I0J787D01*
G01X567362Y438780D02*
G03X568150Y437992I788J0D01*
G01X571693Y440453D02*
G03X571102Y439862I0J-591D01*
G01X574252D02*
G03X573661Y440453I-591J0D01*
G01X573474Y437894D02*
G03I-493J0D01*
G01X566890Y440748D02*
G03X567260Y441007I0J394D01*
G01X568301Y443110D02*
G03X567931Y442851I0J-394D01*
G01X575180D02*
G03X574809Y443110I-370J-135D01*
G01X575851Y441007D02*
G03X576221Y440748I370J135D01*
G01X563111Y480315D02*
G03Y472441I0J-3937D01*
G01X532402D02*
G03Y480315I0J3937D01*
G01X627391Y834055D02*
X545906D01*
G01X627391D02*
X545906D01*
G01X541969Y837992D02*
Y854921D01*
G01Y837992D02*
Y854921D01*
G01Y837992D02*
G03X545906Y834055I3937J0D01*
G01X541969Y837992D02*
G03X545906Y834055I3937J0D01*
G01X627391Y858858D02*
X545906D01*
G01X627391D02*
X545906D01*
G01D02*
G03X541969Y854921I0J-3937D01*
G01X545906Y858858D02*
G03X541969Y854921I0J-3937D01*
G01X563111Y960630D02*
G03Y952756I0J-3937D01*
G01X532402D02*
G03Y960630I0J3937D01*
G01X563111D02*
X725552D01*
G01X543711Y1385233D02*
Y1400833D01*
X536496Y1389653D01*
X546246D01*
G01X629726Y-777373D02*
X1811321D01*
G01X634526Y73005D02*
X634567Y73013D01*
G01X632913Y71654D02*
X633931D01*
G01X636063Y72638D02*
X632913D01*
G01Y72734D02*
X636063D01*
G01X634345Y72795D02*
X634296D01*
G01X634764D02*
X634567D01*
G01X634559Y72837D02*
X634715D01*
G01Y72963D02*
X634559D01*
G01X634567Y73013D02*
X634715D01*
G01X632913Y73126D02*
X636063D01*
G01X634296Y73189D02*
X634345D01*
G01X634715D02*
X634764D01*
G01X633110Y73228D02*
X635866D01*
G01X635276Y75197D02*
X633701D01*
G01X633110Y76378D02*
X633701D01*
G01X636063Y76480D02*
X632913D01*
G01X636063Y76872D02*
X632913D01*
G01X636063Y76969D02*
X632913D01*
G01X633931Y77953D02*
X632913D01*
G01X634567Y72795D02*
X634526Y72804D01*
G01X634534Y72846D02*
X634559Y72837D01*
G01X634526Y72804D02*
X634493Y72829D01*
G01X634518Y72862D02*
X634534Y72846D01*
G01X634493Y72829D02*
X634469Y72862D01*
G01X634559Y72963D02*
X634534Y72954D01*
G01X634469Y72862D02*
X634460Y72887D01*
G01X634509D02*
X634518Y72862D01*
G01X632913Y71654D02*
Y77953D01*
G01X633110D02*
Y76378D01*
G01Y71654D02*
Y73228D01*
G01X633701Y75197D02*
Y76378D01*
G01X634296Y72795D02*
Y73189D01*
G01X634345D02*
Y72862D01*
G01X634394Y72921D02*
Y72854D01*
G01X634460Y72887D02*
Y72921D01*
G01X634509Y72913D02*
Y72887D01*
G01X634715Y72837D02*
Y72963D01*
G01Y73013D02*
Y73189D01*
G01X634764D02*
Y72795D01*
G01X634493Y72980D02*
X634526Y73005D01*
G01X634460Y72921D02*
X634469Y72946D01*
G01X634518Y72938D02*
X634509Y72913D01*
G01X634469Y72946D02*
X634493Y72980D01*
G01X634345Y72862D02*
X634394Y72921D01*
G01Y72854D02*
X634345Y72795D01*
G01X634534Y72954D02*
X634518Y72938D01*
G01X633931Y77953D02*
G03X635045I557J196D01*
G01Y71654D02*
G03X633931I-557J-197D01*
G01X634526Y73005D02*
X634567Y73013D01*
G01X632913Y71654D02*
X633931D01*
G01X636063Y72638D02*
X632913D01*
G01Y72734D02*
X636063D01*
G01X634346Y72795D02*
X634296D01*
G01X634764D02*
X634567D01*
G01X634559Y72837D02*
X634715D01*
G01Y72963D02*
X634559D01*
G01X634567Y73013D02*
X634715D01*
G01X632913Y73126D02*
X636063D01*
G01X634296Y73189D02*
X634346D01*
G01X634715D02*
X634764D01*
G01X633110Y73228D02*
X635866D01*
G01X635276Y75197D02*
X633701D01*
G01X633110Y76378D02*
X633701D01*
G01X636063Y76480D02*
X632913D01*
G01X636063Y76872D02*
X632913D01*
G01X636063Y76969D02*
X632913D01*
G01X633931Y77953D02*
X632913D01*
G01X634567Y72795D02*
X634526Y72804D01*
G01X634534Y72846D02*
X634559Y72837D01*
G01X634526Y72804D02*
X634493Y72829D01*
G01X634518Y72862D02*
X634534Y72846D01*
G01X634493Y72829D02*
X634469Y72862D01*
G01X634559Y72963D02*
X634534Y72954D01*
G01X634469Y72862D02*
X634461Y72887D01*
G01X634510D02*
X634518Y72862D01*
G01X632913Y71654D02*
Y77953D01*
G01X633110D02*
Y76378D01*
G01Y71654D02*
Y73228D01*
G01X633701Y75197D02*
Y76378D01*
G01X634296Y72795D02*
Y73189D01*
G01X634346D02*
Y72862D01*
G01X634395Y72921D02*
Y72854D01*
G01X634461Y72887D02*
Y72921D01*
G01X634510Y72913D02*
Y72887D01*
G01X634715Y72837D02*
Y72963D01*
G01Y73013D02*
Y73189D01*
G01X634764D02*
Y72795D01*
G01X634493Y72980D02*
X634526Y73005D01*
G01X634461Y72921D02*
X634469Y72946D01*
G01X634518Y72938D02*
X634510Y72913D01*
G01X634469Y72946D02*
X634493Y72980D01*
G01X634346Y72862D02*
X634395Y72921D01*
G01Y72854D02*
X634346Y72795D01*
G01X634534Y72954D02*
X634518Y72938D01*
G01X633931Y77953D02*
G03X635045I557J196D01*
G01Y71654D02*
G03X633931I-557J-197D01*
G01X636457Y132035D02*
X624646D01*
G01X636457D02*
X624646D01*
G01X620709Y135972D02*
Y312846D01*
G01Y135972D02*
Y312846D01*
G01Y135972D02*
G03X622708Y132545I3937J0D01*
G01X620709Y135972D02*
G03X622675Y132564I3937J0D01*
G01X622708Y132545D02*
G03X624646Y132035I1938J3427D01*
G01X622675Y132564D02*
G03X624646Y132035I1971J3409D01*
G01X603609Y156909D02*
Y154409D01*
G01X609209Y158909D02*
Y174909D01*
G01X620709Y326909D02*
Y121909D01*
G01D02*
Y120413D01*
G01Y135972D02*
Y312846D01*
G01Y135972D02*
Y312846D01*
G01X622709Y298409D02*
Y150409D01*
G01Y145909D02*
Y139909D01*
G01Y150409D02*
Y145909D01*
G01Y139909D02*
Y121909D01*
G01X620709Y135972D02*
G03X622708Y132545I3937J0D01*
G01X620709Y135972D02*
G03X622675Y132564I3937J0D01*
G01D02*
G03X624646Y132035I1971J3409D01*
G01X636457D02*
X624646D01*
G01X603609Y156909D02*
Y154409D01*
G01X609209Y158909D02*
Y174909D01*
G01X620709Y326909D02*
Y121909D01*
G01D02*
Y120413D01*
G01X622709Y298409D02*
Y150409D01*
G01Y145909D02*
Y139909D01*
G01Y150409D02*
Y145909D01*
G01Y139909D02*
Y121909D01*
G01X578979Y162909D02*
G03X582439I1730J-1019D01*
G01X608602Y136909D02*
G03I-7893J0D01*
G01X608209D02*
G03I-7500J0D01*
G01X592717Y161890D02*
G03I-2008J0D01*
G01X602717D02*
G03I-2008J0D01*
G01X620709Y135972D02*
G03X622675Y132564I3937J0D01*
G01X622709Y132545D02*
G03X624646Y132035I1938J3427D01*
G01X622675Y132564D02*
G03X622709Y132545I1937J3427D01*
G01X578979Y162909D02*
G03X582438I1729J-1019D01*
G01X578979D01*
G01X608602Y136909D02*
G03X592815Y136910I-7894J1D01*
G03X608602Y136909I7894J-1D01*
G01X608209D02*
G03X593208Y136910I-7500J1D01*
G03X608209Y136909I7500J-1D01*
G01X592717Y161890D02*
G03X588700Y161889I-2008J-1D01*
G03X592717Y161890I2008J0D01*
G01X602717D02*
G03X598700Y161889I-2008J-1D01*
G03X602717Y161890I2008J0D01*
G01X605854Y160492D02*
X603492D01*
G01X603743Y160787D02*
X604497D01*
G01X604799D02*
X605854D01*
G01X579459Y161059D02*
X581959D01*
G01X589459D02*
X591959D01*
G01X599459D02*
X601959D01*
G01X604196Y162018D02*
X604045D01*
G01Y162313D02*
X604246D01*
G01Y162707D02*
X603844D01*
G01X601959Y162759D02*
X599459D01*
G01X591959D02*
X589459D01*
G01X581959D02*
X579459D01*
G01X605854Y163002D02*
X603894D01*
G01X603492Y163297D02*
X605854D01*
G01X579459Y171059D02*
X581959D01*
G01X589459D02*
X591959D01*
G01X599459D02*
X601959D01*
G01Y172759D02*
X599459D01*
G01X591959D02*
X589459D01*
G01X581959D02*
X579459D01*
G01Y181059D02*
X581959D01*
G01X589459D02*
X591959D01*
G01X599459D02*
X601959D01*
G01Y182759D02*
X599459D01*
G01X591959D02*
X589459D01*
G01X581959D02*
X579459D01*
G01Y191059D02*
X581959D01*
G01X589459D02*
X591959D01*
G01X599459D02*
X601959D01*
G01Y192759D02*
X599459D01*
G01X591959D02*
X589459D01*
G01X581959D02*
X579459D01*
G01X610009Y199409D02*
X588709D01*
G01Y203109D02*
X610009D01*
G01X588709Y205709D02*
X610009D01*
G01X588709Y213109D02*
X610009D01*
G01X588709Y215709D02*
X610009D01*
G01X604346Y161969D02*
X604196Y162018D01*
G01X604246Y162313D02*
X604397Y162264D01*
G01D02*
X604598Y162116D01*
G01X603844Y162707D02*
X603492Y163002D01*
G01X603894D02*
X604246Y162707D01*
G01X603894Y162264D02*
X604045Y162313D01*
G01Y162018D02*
X603894Y161969D01*
G01X604447Y161870D02*
X604346Y161969D01*
G01X604598Y162116D02*
X604748Y161919D01*
G01X603693Y162116D02*
X603894Y162264D01*
G01X604497Y161722D02*
X604447Y161870D01*
G01X579409Y215709D02*
Y213109D01*
G01Y205709D02*
Y203109D01*
G01X579459Y192759D02*
Y191059D01*
G01Y182759D02*
Y181059D01*
G01Y172759D02*
Y171059D01*
G01Y162759D02*
Y161059D01*
G01X581959D02*
Y162759D01*
G01Y171059D02*
Y172759D01*
G01Y181059D02*
Y182759D01*
G01Y191059D02*
Y192759D01*
G01X582009Y203109D02*
Y205709D01*
G01Y213109D02*
Y215709D01*
G01X588709Y249409D02*
Y199409D01*
G01Y190909D02*
Y182909D01*
G01Y170909D02*
Y162909D01*
G01X589409Y215709D02*
Y213109D01*
G01Y205709D02*
Y203109D01*
G01X589459Y192759D02*
Y191059D01*
G01Y182759D02*
Y181059D01*
G01Y172759D02*
Y171059D01*
G01Y162759D02*
Y161059D01*
G01X591959D02*
Y162759D01*
G01Y171059D02*
Y172759D01*
G01Y181059D02*
Y182759D01*
G01Y191059D02*
Y192759D01*
G01X592009Y203109D02*
Y205709D01*
G01Y213109D02*
Y215709D01*
G01X603543Y161919D02*
X603693Y162116D01*
G01X603894Y161969D02*
X603794Y161870D01*
G01X604748Y161919D02*
X604799Y161673D01*
G01X599409Y215709D02*
Y213109D01*
G01Y205709D02*
Y203109D01*
G01X599459Y192759D02*
Y191059D01*
G01Y182759D02*
Y181059D01*
G01Y172759D02*
Y171059D01*
G01Y162759D02*
Y161059D01*
G01X601959D02*
Y162759D01*
G01Y171059D02*
Y172759D01*
G01Y181059D02*
Y182759D01*
G01Y191059D02*
Y192759D01*
G01X602009Y203109D02*
Y205709D01*
G01Y213109D02*
Y215709D01*
G01X603492Y160492D02*
Y161673D01*
G01Y163002D02*
Y163297D01*
G01X603609Y199409D02*
Y196909D01*
G01X603743Y161722D02*
Y160787D01*
G01X604497D02*
Y161722D01*
G01X604799Y161673D02*
Y160787D01*
G01X605854Y163297D02*
Y163002D01*
G01Y160787D02*
Y160492D01*
G01X609209Y178909D02*
Y194909D01*
G01X610009Y249409D02*
Y199409D01*
G01X603492Y161673D02*
X603543Y161919D01*
G01X603794Y161870D02*
X603743Y161722D01*
G01X578956Y170909D02*
G03X582461I1752J981D01*
G01X582438Y162909D02*
G03X578979I-1730J-1019D01*
G01X578956Y190909D02*
G03X582461I1752J981D01*
G01X582438Y182909D02*
G03X578979I-1730J-1019D01*
G01X582239Y203109D02*
G03Y205710I-1530J1301D01*
G01X579217Y205753D02*
G03X579179Y203109I1492J-1344D01*
G01X582239Y205710D02*
G03X579217Y205753I-1530J-1301D01*
G01X579179Y203109D02*
G03X582239I1530J1300D01*
G01Y213109D02*
G03Y215710I-1530J1300D01*
G01X579217Y215753D02*
G03X579179Y213109I1492J-1344D01*
G01X582239Y215710D02*
G03X579217Y215753I-1530J-1301D01*
G01X579179Y213109D02*
G03X582239I1530J1300D01*
G01X605854Y160492D02*
X603492D01*
G01X603744Y160787D02*
X604498D01*
G01X604799D02*
X605854D01*
G01X579459Y161059D02*
X581959D01*
G01X589459D02*
X591959D01*
G01X599459D02*
X601959D01*
G01X604196Y162018D02*
X604045D01*
G01Y162313D02*
X604246D01*
G01Y162707D02*
X603844D01*
G01X601959Y162759D02*
X599459D01*
G01X591959D02*
X589459D01*
G01X581959D02*
X579459D01*
G01X605854Y163002D02*
X603894D01*
G01X603492Y163297D02*
X605854D01*
G01X579459Y171059D02*
X581959D01*
G01X589459D02*
X591959D01*
G01X599459D02*
X601959D01*
G01Y172759D02*
X599459D01*
G01X591959D02*
X589459D01*
G01X581959D02*
X579459D01*
G01Y181059D02*
X581959D01*
G01X589459D02*
X591959D01*
G01X599459D02*
X601959D01*
G01Y182759D02*
X599459D01*
G01X591959D02*
X589459D01*
G01X581959D02*
X579459D01*
G01Y191059D02*
X581959D01*
G01X589459D02*
X591959D01*
G01X599459D02*
X601959D01*
G01Y192759D02*
X599459D01*
G01X591959D02*
X589459D01*
G01X581959D02*
X579459D01*
G01X610009Y199409D02*
X588709D01*
G01Y203109D02*
X610009D01*
G01X588709Y205709D02*
X610009D01*
G01X588709Y213109D02*
X610009D01*
G01X588709Y215709D02*
X610009D01*
G01X604347Y161969D02*
X604196Y162018D01*
G01X604246Y162313D02*
X604397Y162264D01*
G01D02*
X604598Y162116D01*
G01X603844Y162707D02*
X603492Y163002D01*
G01X603894D02*
X604246Y162707D01*
G01X603894Y162264D02*
X604045Y162313D01*
G01Y162018D02*
X603894Y161969D01*
G01X604447Y161870D02*
X604347Y161969D01*
G01X604598Y162116D02*
X604749Y161919D01*
G01X603693Y162116D02*
X603894Y162264D01*
G01X604498Y161722D02*
X604447Y161870D01*
G01X579409Y215709D02*
Y213109D01*
G01Y205709D02*
Y203109D01*
G01X579459Y192759D02*
Y191059D01*
G01Y182759D02*
Y181059D01*
G01Y172759D02*
Y171059D01*
G01Y162759D02*
Y161059D01*
G01X581959D02*
Y162759D01*
G01Y171059D02*
Y172759D01*
G01Y181059D02*
Y182759D01*
G01Y191059D02*
Y192759D01*
G01X582009Y203109D02*
Y205709D01*
G01Y213109D02*
Y215709D01*
G01X588709Y249409D02*
Y199409D01*
G01Y190909D02*
Y182909D01*
G01Y170909D02*
Y162909D01*
G01X589409Y215709D02*
Y213109D01*
G01Y205709D02*
Y203109D01*
G01X589459Y192759D02*
Y191059D01*
G01Y182759D02*
Y181059D01*
G01Y172759D02*
Y171059D01*
G01Y162759D02*
Y161059D01*
G01X591959D02*
Y162759D01*
G01Y171059D02*
Y172759D01*
G01Y181059D02*
Y182759D01*
G01Y191059D02*
Y192759D01*
G01X592009Y203109D02*
Y205709D01*
G01Y213109D02*
Y215709D01*
G01X603543Y161919D02*
X603693Y162116D01*
G01X603894Y161969D02*
X603794Y161870D01*
G01X604749Y161919D02*
X604799Y161673D01*
G01X599409Y215709D02*
Y213109D01*
G01Y205709D02*
Y203109D01*
G01X599459Y192759D02*
Y191059D01*
G01Y182759D02*
Y181059D01*
G01Y172759D02*
Y171059D01*
G01Y162759D02*
Y161059D01*
G01X601959D02*
Y162759D01*
G01Y171059D02*
Y172759D01*
G01Y181059D02*
Y182759D01*
G01Y191059D02*
Y192759D01*
G01X602009Y203109D02*
Y205709D01*
G01Y213109D02*
Y215709D01*
G01X603492Y160492D02*
Y161673D01*
G01Y163002D02*
Y163297D01*
G01X603609Y199409D02*
Y196909D01*
G01X603744Y161722D02*
Y160787D01*
G01X604498D02*
Y161722D01*
G01X604799Y161673D02*
Y160787D01*
G01X605854Y163297D02*
Y163002D01*
G01Y160787D02*
Y160492D01*
G01X609209Y178909D02*
Y194909D01*
G01X610009Y249409D02*
Y199409D01*
G01X603492Y161673D02*
X603543Y161919D01*
G01X603794Y161870D02*
X603744Y161722D01*
G01X582461Y170909D02*
G03X578957I-1752J981D01*
G01D02*
G03X582461I1752J981D01*
G01X582439Y162909D02*
G03X578979I-1730J-1019D01*
G01X582239Y203109D02*
G03Y205709I-1530J1300D01*
G01X579217Y205753D02*
G03X579179Y203109I1492J-1344D01*
G01X582461Y190909D02*
G03X578957I-1752J981D01*
G01X578979Y182909D02*
G03X582439I1730J-1019D01*
G01X582239Y205709D02*
G03X579217Y205753I-1530J-1300D01*
G01X579179Y203109D02*
G03X582239I1530J1300D01*
G01X578957Y190909D02*
G03X582461I1752J981D01*
G01X582439Y182909D02*
G03X578979I-1730J-1019D01*
G01X582239Y213109D02*
G03Y215709I-1530J1300D01*
G01X579217Y215753D02*
G03X579179Y213109I1492J-1344D01*
G01X582239Y215709D02*
G03X579217Y215753I-1530J-1300D01*
G01X579179Y213109D02*
G03X582239I1530J1300D01*
G01X592717Y171890D02*
G03I-2008J0D01*
G01X602717D02*
G03I-2008J0D01*
G01X592717Y181890D02*
G03I-2008J0D01*
G01Y204409D02*
G03I-2008J0D01*
G01Y191890D02*
G03I-2008J0D01*
G01Y214409D02*
G03I-2008J0D01*
G01X602717Y191890D02*
G03I-2008J0D01*
G01Y181890D02*
G03I-2008J0D01*
G01Y204409D02*
G03I-2008J0D01*
G01Y214409D02*
G03I-2008J0D01*
G01X582461Y170909D02*
G03X578956I-1753J981D01*
G01X582461D01*
G01X592717Y171890D02*
G03X588700Y171889I-2008J-1D01*
G03X592717Y171890I2008J1D01*
G01X602717D02*
G03X598700Y171889I-2008J-1D01*
G03X602717Y171890I2008J1D01*
G01X582461Y190909D02*
G03X578956I-1753J981D01*
G01X582461D01*
G01X578979Y182909D02*
G03X582438I1729J-1019D01*
G01X578979D01*
G01X592717Y181890D02*
G03X588700Y181889I-2008J-1D01*
G03X592717Y181890I2008J0D01*
G01Y191890D02*
G03X588700Y191889I-2008J-1D01*
G03X592717Y191890I2008J0D01*
G01Y204409D02*
G03X588700Y204410I-2008J1D01*
G03X592717Y204409I2008J0D01*
G01X602717Y191890D02*
G03X598700Y191889I-2008J-1D01*
G03X602717Y191890I2008J0D01*
G01Y181890D02*
G03X598700Y181889I-2008J-1D01*
G03X602717Y181890I2008J0D01*
G01Y204409D02*
G03X598700Y204410I-2008J1D01*
G03X602717Y204409I2008J0D01*
G01X592717Y214409D02*
G03X588700Y214410I-2008J0D01*
G03X592717Y214409I2008J-1D01*
G01X602717D02*
G03X598700Y214410I-2008J0D01*
G03X602717Y214409I2008J-1D01*
G01X588709Y223109D02*
X610009D01*
G01X588709Y225709D02*
X610009D01*
G01X588709Y233109D02*
X610009D01*
G01X588709Y235709D02*
X610009D01*
G01X588709Y243109D02*
X610009D01*
G01X588709Y245709D02*
X610009D01*
G01Y249409D02*
X588709D01*
G01X579459Y256059D02*
X581959D01*
G01X589459D02*
X591959D01*
G01X599459D02*
X601959D01*
G01Y257759D02*
X599459D01*
G01X591959D02*
X589459D01*
G01X581959D02*
X579459D01*
G01Y266059D02*
X581959D01*
G01X589459D02*
X591959D01*
G01X599459D02*
X601959D01*
G01Y267759D02*
X599459D01*
G01X591959D02*
X589459D01*
G01X581959D02*
X579459D01*
G01X579409Y245709D02*
Y243109D01*
G01Y235709D02*
Y233109D01*
G01Y225709D02*
Y223109D01*
G01X579459Y267759D02*
Y266059D01*
G01Y257759D02*
Y256059D01*
G01X581959D02*
Y257759D01*
G01Y266059D02*
Y267759D01*
G01X582009Y223109D02*
Y225709D01*
G01Y233109D02*
Y235709D01*
G01Y243109D02*
Y245709D01*
G01X588709Y265909D02*
Y257909D01*
G01X589409Y245709D02*
Y243109D01*
G01Y235709D02*
Y233109D01*
G01Y225709D02*
Y223109D01*
G01X589459Y267759D02*
Y266059D01*
G01Y257759D02*
Y256059D01*
G01X591959D02*
Y257759D01*
G01Y266059D02*
Y267759D01*
G01X592009Y223109D02*
Y225709D01*
G01Y233109D02*
Y235709D01*
G01Y243109D02*
Y245709D01*
G01X599409D02*
Y243109D01*
G01Y235709D02*
Y233109D01*
G01Y225709D02*
Y223109D01*
G01X599459Y267759D02*
Y266059D01*
G01Y257759D02*
Y256059D01*
G01X601959D02*
Y257759D01*
G01Y266059D02*
Y267759D01*
G01X602009Y223109D02*
Y225709D01*
G01Y233109D02*
Y235709D01*
G01Y243109D02*
Y245709D01*
G01X603609Y251909D02*
Y249409D01*
G01X609209Y253909D02*
Y269909D01*
G01Y273909D02*
Y289909D01*
G01X582239Y233109D02*
G03Y235710I-1530J1300D01*
G01X579217Y235753D02*
G03X579179Y233109I1492J-1344D01*
G01X582239Y223109D02*
G03Y225710I-1530J1300D01*
G01X579217Y225753D02*
G03X579179Y223109I1492J-1344D01*
G01X582239Y235710D02*
G03X579217Y235753I-1530J-1301D01*
G01X579179Y233109D02*
G03X582239I1530J1300D01*
G01Y225710D02*
G03X579217Y225753I-1530J-1301D01*
G01X579179Y223109D02*
G03X582239I1530J1300D01*
G01Y243109D02*
G03Y245710I-1530J1300D01*
G01X579217Y245753D02*
G03X579179Y243109I1492J-1344D01*
G01X582239Y245710D02*
G03X579217Y245753I-1530J-1301D01*
G01X579179Y243109D02*
G03X582239I1530J1300D01*
G01X578979Y265909D02*
G03X582438I1729J1020D01*
G01X582461Y257909D02*
G03X578956I-1753J-980D01*
G01X588709Y223109D02*
X610009D01*
G01X588709Y225709D02*
X610009D01*
G01X588709Y233109D02*
X610009D01*
G01X588709Y235709D02*
X610009D01*
G01X588709Y243109D02*
X610009D01*
G01X588709Y245709D02*
X610009D01*
G01Y249409D02*
X588709D01*
G01X579459Y256059D02*
X581959D01*
G01X589459D02*
X591959D01*
G01X599459D02*
X601959D01*
G01Y257759D02*
X599459D01*
G01X591959D02*
X589459D01*
G01X581959D02*
X579459D01*
G01Y266059D02*
X581959D01*
G01X589459D02*
X591959D01*
G01X599459D02*
X601959D01*
G01Y267759D02*
X599459D01*
G01X591959D02*
X589459D01*
G01X581959D02*
X579459D01*
G01X579409Y245709D02*
Y243109D01*
G01Y235709D02*
Y233109D01*
G01Y225709D02*
Y223109D01*
G01X579459Y267759D02*
Y266059D01*
G01Y257759D02*
Y256059D01*
G01X581959D02*
Y257759D01*
G01Y266059D02*
Y267759D01*
G01X582009Y223109D02*
Y225709D01*
G01Y233109D02*
Y235709D01*
G01Y243109D02*
Y245709D01*
G01X588709Y265909D02*
Y257909D01*
G01X589409Y245709D02*
Y243109D01*
G01Y235709D02*
Y233109D01*
G01Y225709D02*
Y223109D01*
G01X589459Y267759D02*
Y266059D01*
G01Y257759D02*
Y256059D01*
G01X591959D02*
Y257759D01*
G01Y266059D02*
Y267759D01*
G01X592009Y223109D02*
Y225709D01*
G01Y233109D02*
Y235709D01*
G01Y243109D02*
Y245709D01*
G01X599409D02*
Y243109D01*
G01Y235709D02*
Y233109D01*
G01Y225709D02*
Y223109D01*
G01X599459Y267759D02*
Y266059D01*
G01Y257759D02*
Y256059D01*
G01X601959D02*
Y257759D01*
G01Y266059D02*
Y267759D01*
G01X602009Y223109D02*
Y225709D01*
G01Y233109D02*
Y235709D01*
G01Y243109D02*
Y245709D01*
G01X603609Y251909D02*
Y249409D01*
G01X609209Y253909D02*
Y269909D01*
G01Y273909D02*
Y289909D01*
G01X582239Y233109D02*
G03Y235709I-1530J1300D01*
G01X579217Y235753D02*
G03X579179Y233109I1492J-1344D01*
G01X582239Y223109D02*
G03Y225709I-1530J1300D01*
G01X579217Y225753D02*
G03X579179Y223109I1492J-1344D01*
G01X582239Y235709D02*
G03X579217Y235753I-1530J-1300D01*
G01X579179Y233109D02*
G03X582239I1530J1300D01*
G01Y225709D02*
G03X579217Y225753I-1530J-1300D01*
G01X579179Y223109D02*
G03X582239I1530J1300D01*
G01X592717Y234409D02*
G03I-2008J0D01*
G01Y224409D02*
G03I-2008J0D01*
G01X602717Y234409D02*
G03I-2008J0D01*
G01Y224409D02*
G03I-2008J0D01*
G01X582239Y243109D02*
G03Y245709I-1530J1300D01*
G01X579217Y245753D02*
G03X579179Y243109I1492J-1344D01*
G01X578957Y257909D02*
G03X582461I1752J-980D01*
G01X582239Y245709D02*
G03X579217Y245753I-1530J-1300D01*
G01X579179Y243109D02*
G03X582239I1530J1300D01*
G01X582461Y257909D02*
G03X578957I-1752J-980D01*
G01X582439Y265909D02*
G03X578979I-1730J1020D01*
G01D02*
G03X582439I1730J1020D01*
G01X592717Y256929D02*
G03I-2008J0D01*
G01X602717D02*
G03I-2008J0D01*
G01X592717Y244409D02*
G03I-2008J0D01*
G01X602717D02*
G03I-2008J0D01*
G01Y266929D02*
G03I-2008J0D01*
G01X592717D02*
G03I-2008J0D01*
G01Y234409D02*
G03X588700Y234410I-2008J0D01*
G03X592717Y234409I2008J-1D01*
G01Y224409D02*
G03X588700Y224410I-2008J0D01*
G03X592717Y224409I2008J-1D01*
G01X602717Y234409D02*
G03X598700Y234410I-2008J0D01*
G03X602717Y234409I2008J-1D01*
G01Y224409D02*
G03X598700Y224410I-2008J0D01*
G03X602717Y224409I2008J-1D01*
G01X582438Y265909D02*
G03X578979I-1730J1020D01*
G01X582438D01*
G01X578956Y257909D02*
G03X582461I1752J-980D01*
G01X578956D01*
G01X592717Y256929D02*
G03X588700I-2008J0D01*
G03X592717I2008J0D01*
G01Y244409D02*
G03X588700Y244410I-2008J0D01*
G03X592717Y244409I2008J-1D01*
G01Y266929D02*
G03X588700I-2008J0D01*
G03X592717I2008J0D01*
G01X602717Y256929D02*
G03X598700I-2008J0D01*
G03X602717I2008J0D01*
G01Y244409D02*
G03X598700Y244410I-2008J0D01*
G03X602717Y244409I2008J-1D01*
G01Y266929D02*
G03X598700I-2008J0D01*
G03X602717I2008J0D01*
G01X620709Y312657D02*
Y311161D01*
G01X636457Y316783D02*
X624646D01*
G01X636457D02*
X624646D01*
G01X622708Y316274D02*
G03X620709Y312846I1938J-3427D01*
G01X622675Y316255D02*
G03X620709Y312846I1971J-3408D01*
G01X624646Y316783D02*
G03X622708Y316274I-2J-3937D01*
G01X624646Y316783D02*
G03X622675Y316255I-1J-3937D01*
G01X579459Y276059D02*
X581959D01*
G01X589459D02*
X591959D01*
G01X599459D02*
X601959D01*
G01Y277759D02*
X599459D01*
G01X591959D02*
X589459D01*
G01X581959D02*
X579459D01*
G01Y286059D02*
X581959D01*
G01X589459D02*
X591959D01*
G01X599459D02*
X601959D01*
G01Y287759D02*
X599459D01*
G01X591959D02*
X589459D01*
G01X581959D02*
X579459D01*
G01D02*
Y286059D01*
G01Y277759D02*
Y276059D01*
G01X581959D02*
Y277759D01*
G01Y286059D02*
Y287759D01*
G01X588709Y285909D02*
Y277909D01*
G01X589459Y287759D02*
Y286059D01*
G01Y277759D02*
Y276059D01*
G01X591959D02*
Y277759D01*
G01Y286059D02*
Y287759D01*
G01X599459D02*
Y286059D01*
G01Y277759D02*
Y276059D01*
G01X601959D02*
Y277759D01*
G01Y286059D02*
Y287759D01*
G01X603609Y294409D02*
Y291909D01*
G01X620709Y328406D02*
Y326909D01*
G01X622709Y308909D02*
Y302909D01*
G01D02*
Y298409D01*
G01Y308909D02*
Y326909D01*
G01X582461Y277909D02*
G03X578956I-1753J-980D01*
G01X578979Y285909D02*
G03X582438I1729J1020D01*
G01X622708Y316274D02*
G03X620709Y312846I1938J-3427D01*
G01X622675Y316255D02*
G03X620709Y312846I1971J-3408D01*
G01X624646Y316783D02*
G03X622675Y316255I-1J-3937D01*
G01X579459Y276059D02*
X581959D01*
G01X589459D02*
X591959D01*
G01X599459D02*
X601959D01*
G01Y277759D02*
X599459D01*
G01X591959D02*
X589459D01*
G01X581959D02*
X579459D01*
G01Y286059D02*
X581959D01*
G01X589459D02*
X591959D01*
G01X599459D02*
X601959D01*
G01Y287759D02*
X599459D01*
G01X591959D02*
X589459D01*
G01X581959D02*
X579459D01*
G01X636457Y316783D02*
X624646D01*
G01X579459Y287759D02*
Y286059D01*
G01Y277759D02*
Y276059D01*
G01X581959D02*
Y277759D01*
G01Y286059D02*
Y287759D01*
G01X588709Y285909D02*
Y277909D01*
G01X589459Y287759D02*
Y286059D01*
G01Y277759D02*
Y276059D01*
G01X591959D02*
Y277759D01*
G01Y286059D02*
Y287759D01*
G01X599459D02*
Y286059D01*
G01Y277759D02*
Y276059D01*
G01X601959D02*
Y277759D01*
G01Y286059D02*
Y287759D01*
G01X603609Y294409D02*
Y291909D01*
G01X620709Y328406D02*
Y326909D01*
G01X622709Y308909D02*
Y302909D01*
G01D02*
Y298409D01*
G01Y308909D02*
Y326909D01*
G01X582439Y285909D02*
G03X578979I-1730J1020D01*
G01X578957Y277909D02*
G03X582461I1752J-980D01*
G01X578979Y285909D02*
G03X582439I1730J1020D01*
G01X582461Y277909D02*
G03X578957I-1752J-980D01*
G01X592717Y276929D02*
G03I-2008J0D01*
G01X602717Y286929D02*
G03I-2008J0D01*
G01Y276929D02*
G03I-2008J0D01*
G01X592717Y286929D02*
G03I-2008J0D01*
G01X608602Y311909D02*
G03I-7893J0D01*
G01X608209D02*
G03I-7500J0D01*
G01X622675Y316255D02*
G03X620709Y312846I1971J-3408D01*
G01X624646Y316783D02*
G03X622709Y316274I-1J-3937D01*
G01D02*
G03X622675Y316255I1904J-3446D01*
G01X578956Y277909D02*
G03X582461I1752J-980D01*
G01X578956D01*
G01X582438Y285909D02*
G03X578979I-1730J1020D01*
G01X582438D01*
G01X592717Y276929D02*
G03X588700I-2008J0D01*
G03X592717I2008J0D01*
G01Y286929D02*
G03X588700I-2008J0D01*
G03X592717I2008J0D01*
G01X602717D02*
G03X598700I-2008J0D01*
G03X602717I2008J0D01*
G01Y276929D02*
G03X598700I-2008J0D01*
G03X602717I2008J0D01*
G01X608602Y311909D02*
G03X592815Y311910I-7894J0D01*
G03X608602Y311909I7894J-1D01*
G01X608209D02*
G03X593208Y311910I-7500J0D01*
G03X608209Y311909I7500J-1D01*
G01X629574Y379204D02*
X638641Y385248D01*
G01X629574Y379204D02*
X638641Y385248D01*
G01Y347035D02*
X629574Y353079D01*
G01X638641Y347035D02*
X629574Y353079D01*
G01D02*
G03X627391Y353740I-2183J-3276D01*
G01X629574Y353079D02*
G03X627391Y353740I-2183J-3276D01*
G01Y378543D02*
G03X629574Y379205I-2J3937D01*
G01X627391Y378543D02*
G03X629574Y379205I-2J3937D01*
G01X629575Y379204D02*
X638641Y385248D01*
G01X601024Y334252D02*
X624646D01*
G01X620709Y338189D02*
X604961D01*
G01X620000Y349409D02*
X615669D01*
G01X605669D02*
X610000D01*
G01X604961Y352362D02*
X620709D01*
G01X624646Y356299D02*
X601024D01*
G01Y377953D02*
X624646D01*
G01X620709Y381890D02*
X604961D01*
G01X638641Y347035D02*
X629575Y353079D01*
G01X601024Y400000D02*
Y377953D01*
G01Y356299D02*
Y334252D01*
G01X604961Y338189D02*
Y352362D01*
G01Y381890D02*
Y396063D01*
G01X605669Y338189D02*
Y349409D01*
G01Y381890D02*
Y393110D01*
G01X610000D02*
Y381890D01*
G01Y349409D02*
Y338189D01*
G01X615669Y393110D02*
Y381890D01*
G01Y349409D02*
Y338189D01*
G01X620000D02*
Y349409D01*
G01Y381890D02*
Y393110D01*
G01X620709Y396063D02*
Y381890D01*
G01Y352362D02*
Y338189D01*
G01X624646Y334252D02*
Y356299D01*
G01Y377953D02*
Y400000D01*
G01X629575Y353079D02*
G03X627391Y353740I-2184J-3276D01*
G01Y378543D02*
G03X629575Y379204I0J3937D01*
G01X583168Y429996D02*
X583152Y429985D01*
G01X584234Y436146D02*
X584250Y436156D01*
G01X597480Y429528D02*
X593937Y427402D01*
G01X585276Y429764D02*
X583602Y428090D01*
G01D02*
X582913Y427402D01*
G01X589803Y436378D02*
X587441Y434140D01*
G01D02*
X585731Y432520D01*
G01X583168Y429809D02*
X583152Y429789D01*
G01X584234Y436333D02*
X584250Y436353D01*
G01X580748Y433071D02*
X582822Y436378D01*
G01X587441Y429134D02*
X597663Y431139D01*
G01X586124Y428110D02*
X586043Y428094D01*
G01X585896Y428080D02*
X585977Y428096D01*
G01X586817Y428893D02*
X586664Y428864D01*
G01X586735Y429271D02*
X586662Y429257D01*
G01X586704Y436746D02*
X586631Y436731D01*
G01X586630Y437125D02*
X586783Y437155D01*
G01X585936Y437931D02*
X585856Y437915D01*
G01X586044Y428094D02*
X585896Y428080D01*
G01X586124Y428110D02*
X585977Y428096D01*
G01X621314Y423623D02*
X621366Y423626D01*
G01X620000Y393110D02*
X615669D01*
G01X605669D02*
X610000D01*
G01X604961Y396063D02*
X620709D01*
G01X624646Y400000D02*
X601024D01*
G01X587457Y441007D02*
X588128Y442851D01*
G01X621299Y423622D02*
X621314D01*
G01X621299Y424803D02*
X621287D01*
G01X609493Y423622D02*
X609492D01*
G01X624646Y424213D02*
X623071D01*
G01X596102Y425689D02*
X594134D01*
G01X603189Y425787D02*
X602795D01*
G01X605354Y425984D02*
X602795D01*
G01X623071Y426181D02*
X624646D01*
G01Y426511D02*
X623071D01*
G01X605354Y427165D02*
X603976D01*
G01X581142D02*
X585079D01*
G01X593937Y427402D02*
X585079D01*
G01D02*
X581142D01*
G01X624646Y427559D02*
X623071D01*
G01X628386Y427756D02*
X624646D01*
G01X622897D02*
X622677D01*
G01X623071D02*
X622897D01*
G01X618878D02*
X617696D01*
G01X619724D02*
X618878D01*
G01X615795D02*
X614613D01*
G01X617696D02*
X615795D01*
G01X614613D02*
X612711D01*
G01D02*
X611530D01*
G01X609628D02*
X608446D01*
G01X611530D02*
X609628D01*
G01X608446D02*
X606545D01*
G01D02*
X598661D01*
G01X623071D02*
X624646D01*
G01Y429134D02*
X623071D01*
G01X589409D02*
X593346D01*
G01X624646Y429331D02*
X621677D01*
G01D02*
X621620D01*
G01D02*
X620439D01*
G01D02*
X619724D01*
G01X601024Y429528D02*
X597480D01*
G01X589803Y429764D02*
X587441D01*
G01D02*
X585276D01*
G01X580748D02*
X582822D01*
G01X591673Y429789D02*
X584250D01*
G01X584234Y429809D02*
X591673D01*
G01Y429929D02*
X584291D01*
G01X591673Y429985D02*
X584250D01*
G01X584234Y429996D02*
X591673D01*
G01Y430056D02*
X584291D01*
G01X603780Y430709D02*
X604567D01*
G01X607717Y430906D02*
X591772D01*
G01X624646Y431102D02*
X623071D01*
G01X622818D02*
X621637D01*
G01X623071D02*
X622818D01*
G01X621637D02*
X621558D01*
G01D02*
X620377D01*
G01D02*
X618740D01*
G01X624646Y431299D02*
X622283D01*
G01X609411D02*
X608230D01*
G01X610669D02*
X609411D01*
G01X608230D02*
X606328D01*
G01D02*
X593173D01*
G01D02*
X590984D01*
G01X591673Y431483D02*
X584291D01*
G01X590787Y431687D02*
X585472D01*
G01X591673Y431721D02*
X584291D01*
G01Y431779D02*
X591673D01*
G01Y431791D02*
X584291D01*
G01X590787Y432243D02*
X585472D01*
G01X595118Y432283D02*
X587244D01*
G01Y432347D02*
X585472D01*
G01X587244Y432382D02*
X585472D01*
G01X585731Y432520D02*
X587441D01*
G01D02*
X589803D01*
G01X587244Y432579D02*
X585472D01*
G01X587244Y433563D02*
X585472D01*
G01X587244Y433760D02*
X585472D01*
G01X587244Y433794D02*
X585472D01*
G01X595118Y433858D02*
X587244D01*
G01X590787Y433898D02*
X585472D01*
G01X591673Y434350D02*
X584291D01*
G01X591673Y434363D02*
X584291D01*
G01Y434420D02*
X591673D01*
G01X590787Y434455D02*
X585472D01*
G01X591673Y434658D02*
X584291D01*
G01X590984Y434843D02*
X593173D01*
G01D02*
X606130D01*
G01D02*
X608032D01*
G01D02*
X609213D01*
G01D02*
X610669D01*
G01X622283D02*
X624646D01*
G01Y435039D02*
X623071D01*
G01X618740D02*
X620231D01*
G01D02*
X621412D01*
G01D02*
X621552D01*
G01D02*
X622733D01*
G01D02*
X623071D01*
G01X591772Y435236D02*
X607717D01*
G01X604567Y435433D02*
X603780D01*
G01X584291Y436086D02*
X591673D01*
G01Y436146D02*
X584234D01*
G01X591673Y436156D02*
X584250D01*
G01X584291Y436213D02*
X591673D01*
G01Y436333D02*
X584234D01*
G01X591673Y436353D02*
X584250D01*
G01X582822Y436378D02*
X580748D01*
G01X601024Y436614D02*
X597480D01*
G01X624646Y436811D02*
X621513D01*
G01X621337D02*
X620156D01*
G01X621513D02*
X621337D01*
G01X620156D02*
X619724D01*
G01X624646Y437008D02*
X623071D01*
G01X593346D02*
X589409D01*
G01X609492Y424804D02*
X609493D01*
G01X585079Y428083D02*
X585896Y428080D01*
G01X581142Y428100D02*
X585079Y428083D01*
G01X585977Y428096D02*
X585079Y428100D01*
G01D02*
X581142Y428116D01*
G01X586744Y428880D02*
X586100Y428882D01*
G01X585837Y429261D02*
X586662Y429257D01*
G01X586631Y436731D02*
X585806Y436735D01*
G01X621319Y424803D02*
X621299D01*
G01X622494D02*
X622480Y424804D01*
G01X621278Y423623D02*
X621299Y423622D01*
G01X622465Y423623D02*
X622480Y423622D01*
G01X596796Y425135D02*
X596124Y423291D01*
G01X598661Y438386D02*
X605914D01*
G01D02*
X607814D01*
G01D02*
X608996D01*
G01D02*
X610897D01*
G01D02*
X612080D01*
G01D02*
X613981D01*
G01D02*
X615163D01*
G01D02*
X617065D01*
G01D02*
X618246D01*
G01D02*
X619724D01*
G01X623071D02*
X624646D01*
G01X622677D02*
X623071D01*
G01X624646D02*
X628386D01*
G01X624646Y438583D02*
X623071D01*
G01X593937Y438740D02*
X585079D01*
G01D02*
X581142D01*
G01X585079Y438976D02*
X581142D01*
G01X603976D02*
X605354D01*
G01X623071Y439631D02*
X624646D01*
G01Y439961D02*
X623071D01*
G01X602795Y440157D02*
X605354D01*
G01X602795Y440354D02*
X603189D01*
G01X594134Y440453D02*
X596102D01*
G01X623071Y441929D02*
X624646D01*
G01X607951Y442518D02*
X607950D01*
G01X586710Y437141D02*
X586067Y437143D01*
G01X581142Y437950D02*
X585079Y437934D01*
G01D02*
X585936Y437931D01*
G01X622405Y423628D02*
X622465Y423623D01*
G01X621223Y423628D02*
X621278Y423623D01*
G01X597663Y435002D02*
X587441Y437008D01*
G01X585806Y436735D02*
X585837Y429261D01*
G01X586100Y428882D02*
X586067Y437143D01*
G01X586435Y429268D02*
X586405Y436742D01*
G01X586664Y428864D02*
X586662Y429257D01*
G01X586631Y436731D02*
X586630Y437125D01*
G01X586704Y436746D02*
X586735Y429271D01*
G01X586783Y437155D02*
X586817Y428893D01*
G01X578583Y439764D02*
Y438740D01*
G01Y426378D02*
Y427402D01*
G01X578976Y433858D02*
Y432283D01*
G01X579567Y425394D02*
Y423031D01*
G01Y440748D02*
Y443110D01*
G01X579764Y432283D02*
Y433858D01*
G01X580157D02*
Y432283D01*
G01X581142Y438976D02*
Y427165D01*
G01X581929Y434547D02*
Y433858D01*
G01Y432283D02*
Y431594D01*
G01X582224Y432087D02*
Y431791D01*
G01Y434055D02*
Y434350D01*
G01X582421Y432087D02*
Y431791D01*
G01Y434055D02*
Y434350D01*
G01X582520Y432283D02*
Y433858D01*
G01X582913D02*
Y432283D01*
G01X583110Y436213D02*
Y434350D01*
G01Y431791D02*
Y429929D01*
G01X583168Y429809D02*
Y429996D01*
G01Y436146D02*
Y436333D01*
G01X583701Y433858D02*
Y432283D01*
G01Y425394D02*
Y423031D01*
G01Y440748D02*
Y443110D01*
G01X584234Y429809D02*
Y429996D01*
G01Y436146D02*
Y436333D01*
G01X584291Y429929D02*
Y431791D01*
G01Y434350D02*
Y436213D01*
G01X584882Y439764D02*
Y438976D01*
G01D02*
Y438740D01*
G01Y426378D02*
Y427165D01*
G01D02*
Y427402D01*
G01X584980Y434350D02*
Y434055D01*
G01Y432087D02*
Y431791D01*
G01X585079Y427165D02*
Y438976D01*
G01X585170Y433858D02*
Y432283D01*
G01X585177Y434350D02*
Y434055D01*
G01Y432087D02*
Y431791D01*
G01X585276Y433858D02*
Y432283D01*
G01X585472Y432579D02*
Y431594D01*
G01Y434547D02*
Y433563D01*
G01X587244Y433858D02*
Y432283D01*
G01Y425394D02*
Y423031D01*
G01Y440748D02*
Y443110D01*
G01X587350Y433858D02*
Y432283D01*
G01X587441Y437008D02*
Y429134D01*
G01X588819Y433858D02*
Y432283D01*
G01X589409Y425787D02*
Y429134D01*
G01Y437008D02*
Y440354D01*
G01X589606Y432283D02*
Y433858D01*
G01X589803Y438740D02*
Y436544D01*
G01D02*
Y436378D01*
G01Y432520D02*
Y429764D01*
G01X590000Y433858D02*
Y432283D01*
G01X590787Y434547D02*
Y433858D01*
G01Y432283D02*
Y431594D01*
G01X590984Y431299D02*
Y434843D01*
G01X591083Y432087D02*
Y431791D01*
G01Y434055D02*
Y434350D01*
G01X591280Y432087D02*
Y431791D01*
G01Y434055D02*
Y434350D01*
G01X591673Y429789D02*
Y436353D01*
G01X591772Y437402D02*
Y435236D01*
G01Y430906D02*
Y428740D01*
G01X591969Y429724D02*
Y436417D01*
G01X592362Y432283D02*
Y433858D01*
G01X592756D02*
Y432283D01*
G01X593543Y433858D02*
Y432283D01*
G01Y426280D02*
Y426378D01*
G01Y439764D02*
Y439862D01*
G01X595013Y433858D02*
Y432283D01*
G01X595118Y433858D02*
Y432283D01*
G01X602756Y440354D02*
X602750Y440212D01*
G01X602768Y440677D02*
X602756Y440354D01*
G01X602777Y440881D02*
X602768Y440677D01*
G01X603982Y438386D02*
X603957Y437812D01*
G01X605172Y438560D02*
X605193Y438985D01*
G01X606551Y432375D02*
X606517Y431776D01*
G01X602810Y441506D02*
X602802Y441377D01*
G01X605246Y439947D02*
X605264Y440227D01*
G01X606304Y428211D02*
X606273Y427756D01*
G01X619535Y441509D02*
Y441510D01*
G01X620702Y441341D02*
Y441340D01*
G01X613319Y424595D02*
Y424596D01*
G01X612153Y424772D02*
Y424771D01*
G01X604676Y439173D02*
X604699Y438849D01*
G01D02*
X604732Y438386D01*
G01X605340Y428100D02*
X605363Y427756D01*
G01X604732Y438386D02*
X604764Y437904D01*
G01X608996Y438386D02*
X608963Y438861D01*
G01X605898Y438615D02*
X605945Y437926D01*
G01X605178Y430744D02*
X605212Y430164D01*
G01X604999Y433949D02*
X605109Y431971D01*
G01X606292Y431941D02*
X606158Y434344D01*
G01X602983Y440354D02*
X602994Y440055D01*
G01X603328Y426326D02*
X603339Y425984D01*
G01X603319Y426580D02*
X603328Y426326D01*
G01X603311Y426850D02*
X603319Y426580D01*
G01X604494Y426813D02*
X604483Y427165D01*
G01D02*
X604467Y427756D01*
G01X603034Y438742D02*
X603044Y438386D01*
G01X603277Y428081D02*
X603286Y427756D01*
G01D02*
X603294Y427434D01*
G01X603044Y438386D02*
X603060Y437770D01*
G01X604467Y427756D02*
X604450Y428413D01*
G01X603260Y428791D02*
X603277Y428081D01*
G01X603060Y437770D02*
X603077Y437046D01*
G01X604450Y428413D02*
X604431Y429175D01*
G01X603241Y429562D02*
X603260Y428791D01*
G01X603077Y437046D02*
X603096Y436263D01*
G01X604431Y429175D02*
X604413Y430000D01*
G01X604285Y435879D02*
X604263Y436852D01*
G01X603222Y430394D02*
X603241Y429562D01*
G01X603096Y436263D02*
X603115Y435422D01*
G01X604413Y430000D02*
X604393Y430885D01*
G01X603203Y431279D02*
X603222Y430394D01*
G01X604308Y434860D02*
X604285Y435879D01*
G01X603115Y435422D02*
X603131Y434648D01*
G01X604393Y430885D02*
X604372Y431823D01*
G01X603131Y434648D02*
X603203Y431279D01*
G01X604372Y431823D02*
X604308Y434860D01*
G01X596693Y439862D02*
Y439764D01*
G01Y426378D02*
Y426280D01*
G01X597087Y423031D02*
Y425394D01*
G01Y440748D02*
Y443110D01*
G01X597480Y426378D02*
Y429528D01*
G01Y436614D02*
Y439764D01*
G01X598661D02*
Y435236D01*
G01Y430906D02*
Y426378D01*
G01X599646Y423031D02*
Y425394D01*
G01Y440748D02*
Y443110D01*
G01X601024Y438386D02*
Y436614D01*
G01Y427756D02*
Y429528D01*
G01X602205Y440748D02*
Y425394D01*
G01X602795Y423031D02*
Y425984D01*
G01D02*
Y426969D01*
G01Y439173D02*
Y440157D01*
G01D02*
Y443110D01*
G01X602992Y434646D02*
Y431496D01*
G01X603189Y440157D02*
Y439764D01*
G01Y440354D02*
Y440157D01*
G01Y426378D02*
Y425984D01*
G01D02*
Y425787D01*
G01X605354Y425984D02*
Y440157D01*
G01X607717Y435236D02*
Y430906D01*
G01X610669Y434843D02*
Y431299D01*
G01X618740Y431102D02*
Y435039D01*
G01X619724Y438386D02*
Y436811D01*
G01Y427756D02*
Y429331D01*
G01X622283Y431299D02*
Y434843D01*
G01X622677Y429331D02*
Y427756D01*
G01Y436811D02*
Y437500D01*
G01D02*
Y438386D01*
G01X623071Y441929D02*
Y424213D01*
G01X602624Y435396D02*
X602536Y431293D01*
G01X603718Y431299D02*
X603804Y435346D01*
G01X621057Y435509D02*
X620956Y430840D01*
G01X622130Y430528D02*
X622228Y435039D01*
G01D02*
X622247Y435944D01*
G01X603804Y435346D02*
X603823Y436174D01*
G01X620956Y430840D02*
X620937Y429998D01*
G01X602645Y436320D02*
X602624Y435396D01*
G01X621077Y436421D02*
X621057Y435509D01*
G01X622113Y429752D02*
X622130Y430528D01*
G01X603823Y436174D02*
X603841Y436954D01*
G01X620937Y429998D02*
X620919Y429208D01*
G01X622247Y435944D02*
X622267Y436811D01*
G01D02*
X622281Y437417D01*
G01X622087Y428665D02*
X622113Y429752D01*
G01X622281Y437417D02*
X622298Y438069D01*
G01X603635Y427756D02*
X603650Y428374D01*
G01X602704Y438716D02*
X602695Y438386D01*
G01D02*
X602685Y437986D01*
G01X603867Y438022D02*
X603876Y438386D01*
G01X603615Y427067D02*
X603635Y427756D01*
G01X603748Y431589D02*
X603689Y429519D01*
G01X604841Y428496D02*
X604921Y431299D01*
G01X603876Y438386D02*
X603893Y438989D01*
G01D02*
X603900Y439237D01*
G01X602723Y439371D02*
X602704Y438716D01*
G01X603604Y426665D02*
X603615Y427067D01*
G01X604819Y427756D02*
X604841Y428496D01*
G01X603637Y427756D02*
X603617Y427067D01*
G01D02*
X603591Y426281D01*
G01X605000Y433936D02*
X605029Y434843D01*
G01X621169Y439889D02*
X621156Y439473D01*
G01X605029Y434843D02*
X605055Y435608D01*
G01X603583Y426022D02*
X603591Y426281D01*
G01X605055Y435608D02*
X605077Y436243D01*
G01X603596Y426443D02*
X603579Y425934D01*
G01X604763Y425984D02*
X604776Y426370D01*
G01X605153Y438146D02*
X605172Y438560D01*
G01X607728Y432297D02*
X607834Y434212D01*
G01X620097Y432942D02*
X620178Y434393D01*
G01X610750Y431227D02*
X610788Y431889D01*
G01X607655Y431004D02*
X607728Y432297D01*
G01X609624Y432207D02*
X609573Y431299D01*
G01X607834Y434212D02*
X607869Y434843D01*
G01X620178Y434393D02*
X620224Y435216D01*
G01X611138Y437922D02*
X611170Y438386D01*
G01X584250Y429985D02*
X584234Y429996D01*
G01X618609Y432217D02*
X618495Y434270D01*
G01X620489Y427983D02*
X620513Y427350D01*
G01X621693Y427393D02*
X621668Y428037D01*
G01X621494Y432871D02*
X621461Y433783D01*
G01X620463Y428672D02*
X620489Y427983D01*
G01X621668Y428037D02*
X621642Y428736D01*
G01X620298Y433280D02*
X620332Y432363D01*
G01X621642Y428736D02*
X621615Y429487D01*
G01X621527Y431981D02*
X621494Y432871D01*
G01X622910Y427266D02*
X622897Y427751D01*
G01D02*
X622884Y428259D01*
G01X622677Y437500D02*
X622655Y438385D01*
G01X621691Y428710D02*
X621709Y428017D01*
G01X621482Y438047D02*
X621500Y437326D01*
G01X622884Y428259D02*
X622866Y428987D01*
G01X622696Y436699D02*
X622677Y437500D01*
G01X621500Y437326D02*
X621519Y436533D01*
G01X622866Y428987D02*
X622848Y429759D01*
G01X621665Y429851D02*
X621691Y428710D01*
G01X622714Y435947D02*
X622696Y436699D01*
G01X621519Y436533D02*
X621539Y435680D01*
G01X622848Y429759D02*
X622830Y430567D01*
G01X621646Y430676D02*
X621665Y429851D01*
G01X621539Y435680D02*
X621558Y434781D01*
G01X622740Y434756D02*
X622714Y435947D01*
G01X622830Y430567D02*
X622811Y431397D01*
G01X621617Y431998D02*
X621646Y430676D01*
G01X624646Y424213D02*
Y441929D01*
G01X628386Y445276D02*
Y420866D01*
G01X597480Y436614D02*
X593937Y438740D01*
G01X583152Y436156D02*
X583168Y436146D01*
G01X584250Y429789D02*
X584234Y429809D01*
G01X583152Y436353D02*
X583168Y436333D01*
G01X582822Y429764D02*
X580748Y433071D01*
G01X588128Y423291D02*
X587457Y425135D01*
G01X596124Y442851D02*
X596796Y441007D01*
G01X603708Y435440D02*
G03X603643Y438394I-948192J-19386D01*
G01X603033Y427750D02*
G03X603119Y431072I-481490J14127D01*
G01X605471Y436235D02*
G03X605354Y438238I-312357J-17241D01*
G01X603625Y439099D02*
G03X603595Y440178I-264737J-6821D01*
G01X604173Y426503D02*
G03X604196Y427135I-224581J8489D01*
G01X605345Y438395D02*
G03X605306Y439000I-206610J-13015D01*
G01X602993Y426503D02*
G03X603033Y427751I-153196J5535D01*
G01X605306Y439000D02*
G03X605224Y440180I-119589J-7718D01*
G01X604151Y425946D02*
G03X604174Y426503I-72712J3281D01*
G01X586817Y428894D02*
G03X586560Y428893I-52J-19629D01*
G01X586709Y437155D02*
G03X586526Y437154I17J-19811D01*
G01X586783Y437155D02*
G03X586709I-37J-18949D01*
G01X595754Y423031D02*
G03X596124Y423291I0J394D01*
G01X588128D02*
G03X588498Y423031I370J134D01*
G01X596890Y428051D02*
G03I-1280J0D01*
G01X596102Y425689D02*
G03X596693Y426280I1J590D01*
G01X593543D02*
G03X594134Y425689I591J0D01*
G01X596102Y428051D02*
G03I-492J0D01*
G01X593346Y429134D02*
G03X593694Y429712I0J394D01*
G01X597166Y425394D02*
G03X596796Y425135I0J-394D01*
G01X587457D02*
G03X587087Y425394I-370J-135D01*
G01X582421Y432087D02*
G03X582380Y432283I-492J-1D01*
G01X582224Y432087D02*
G03X582149Y432283I-295J0D01*
G01X582224Y431791D02*
G03X582421Y431594I197J0D01*
G01X582018Y434449D02*
G03X581929Y434455I-101J-834D01*
G01X582380Y433858D02*
G03X582421Y434055I-451J197D01*
G01X582149Y433858D02*
G03X582224Y434055I-220J197D01*
G01X585384Y431692D02*
G03X585472Y431687I92J835D01*
G01Y432579D02*
G03X585276Y432537I3J-492D01*
G01X585022Y432283D02*
G03X584980Y432087I450J-199D01*
G01X585472Y432382D02*
G03X585276Y432307I1J-295D01*
G01X585252Y432283D02*
G03X585177Y432087I220J-197D01*
G01X584980Y431594D02*
G03X585177Y431791I0J197D01*
G01X584980Y434055D02*
G03X585022Y433858I492J2D01*
G01X585276Y433604D02*
G03X585472Y433563I197J451D01*
G01X585177Y434055D02*
G03X585252Y433858I296J0D01*
G01X585276Y433835D02*
G03X585472Y433760I197J220D01*
G01X585372Y433800D02*
G03X585472Y433794I105J909D01*
G01X585276Y433816D02*
G03X585372Y433800I185J814D01*
G01X582421Y434547D02*
G03X582224Y434350I0J-197D01*
G01X585177D02*
G03X584980Y434547I-197J0D01*
G01X597663Y431139D02*
G03Y435002I-380J1931D01*
G01X590876Y434449D02*
G03X590787Y434455I-101J-834D01*
G01X591280Y432087D02*
G03X591239Y432283I-492J-1D01*
G01Y433858D02*
G03X591280Y434055I-451J197D01*
G01X591202Y432228D02*
G03X591181Y432243I-210J-272D01*
G01X591083Y432087D02*
G03X591007Y432283I-295J-2D01*
G01Y433858D02*
G03X591083Y434055I-219J198D01*
G01Y431791D02*
G03X591280Y431594I197J0D01*
G01X593694Y436429D02*
G03X593346Y437008I-347J185D01*
G01X591280Y434547D02*
G03X591083Y434350I0J-197D01*
G01X611252Y441594D02*
G03X611239Y441704I-14998J-1717D01*
G01X596890Y437894D02*
G03I-1280J0D01*
G01X586710Y437141D02*
G03Y437154I-791J7D01*
G01X594134Y440453D02*
G03X593543Y439862I0J-591D01*
G01X596693D02*
G03X596102Y440453I-591J0D01*
G01Y437894D02*
G03I-492J0D01*
G01X587087Y440748D02*
G03X587457Y441007I0J394D01*
G01X588498Y443110D02*
G03X588128Y442851I0J-394D01*
G01X596124D02*
G03X595754Y443110I-370J-134D01*
G01X596796Y441007D02*
G03X597166Y440748I370J135D01*
G01X612330Y424779D02*
G03X612336Y424722I22434J2333D01*
G01X609246Y424781D02*
G03X609275Y424533I18661J2056D01*
G01X615431Y424622D02*
G03X615437Y424567I17712J1904D01*
G01X602795Y426969D02*
G03X598629Y425394I1J-6299D01*
G01X602795Y424606D02*
G03X599646Y423031I1J-3937D01*
G01X605354Y429921D02*
G03X604567Y430709I-787J1D01*
G01X603976Y427165D02*
G03X603189Y426378I0J-787D01*
G01X602992Y426503D02*
G03X602794Y426475I2J-727D01*
G01Y425593D02*
G03X602992Y425565I200J699D01*
G01X603204Y426471D02*
G03X602992Y426503I-213J-695D01*
G01X603579Y425983D02*
G03X603583Y426022I-359J56D01*
G01D02*
G03Y426045I-354J12D01*
G01X593446Y430309D02*
G03X593694Y429712I7491J2762D01*
G01Y436429D02*
G03X593446Y435833I7241J-3363D01*
G01D02*
G03Y430309I7491J-2762D01*
G01X605354Y437032D02*
G03Y429109I0J-3961D01*
G01Y435777D02*
G03Y430365I0J-2706D01*
G01X598979Y432079D02*
G03Y434063I-711J992D01*
G01D02*
G03Y432079I-711J-992D01*
G01X603189Y439764D02*
G03X603976Y438976I788J0D01*
G01X604567Y435433D02*
G03X605354Y436220I0J787D01*
G01X603780Y435433D02*
G03X602992Y434646I0J-788D01*
G01Y431496D02*
G03X603780Y430709I787J0D01*
G01X598629Y440748D02*
G03X602795Y439173I4167J4724D01*
G01X599646Y443110D02*
G03X602795Y441535I3150J2362D01*
G01X604591Y438396D02*
G03X604568Y437939I122178J-6378D01*
G01X603343Y439772D02*
G03X603328Y439359I112829J-4305D01*
G01X604625Y439006D02*
G03X604591Y438396I89015J-5267D01*
G01X603360Y440193D02*
G03X603347Y439872I68805J-2947D01*
G01X604654Y439476D02*
G03X604625Y439006I61913J-4056D01*
G01X619745Y436828D02*
G03X619632Y435048I305934J-20315D01*
G01X603883Y427122D02*
G03X603916Y425959I239848J6224D01*
G01X604569Y437939D02*
G03X604470Y435595I205057J-9835D01*
G01X603328Y439359D02*
G03X603297Y438408I194135J-6804D01*
G01X619857Y438404D02*
G03X619745Y436828I134539J-10353D01*
G01X621683Y436827D02*
G03X621640Y435049I789175J-19975D01*
G01X603803Y430700D02*
G03X603868Y427754I776764J15665D01*
G01X603297Y438408D02*
G03X603214Y435190I609652J-17334D01*
G01X604443Y434852D02*
G03X604361Y432379I600842J-21161D01*
G01X603119Y431072D02*
X603124Y431290D01*
G01D02*
X603129Y431484D01*
G01D02*
X603165Y433070D01*
G01D02*
X603201Y434648D01*
G01D02*
X603206Y434852D01*
G01D02*
X603214Y435190D01*
G01X603343Y439772D02*
X603346Y439872D01*
G01X604470Y435595D02*
X604464Y435441D01*
G01D02*
X604443Y434852D01*
G01X604361Y432379D02*
X604326Y431290D01*
G01D02*
X604309Y430713D01*
G01X604217Y427748D02*
X604196Y427135D01*
G01X607074Y431293D02*
X607286Y434847D01*
G01X610157Y431295D02*
X610369Y434844D01*
G01X590959Y434435D02*
X590988Y434427D01*
G01X603883Y427122D02*
Y427134D01*
G01D02*
X603868Y427753D01*
G01X603803Y430699D02*
X603708Y435440D01*
G01X603643Y438393D02*
X603625Y439099D01*
G01X621640Y435049D02*
X621594Y433071D01*
G01D02*
X621553Y431239D01*
G01D02*
X621549Y431093D01*
G01X605345Y438395D02*
X605354Y438238D01*
G01X605495Y435798D02*
X605471Y436235D01*
G01X621985Y441346D02*
Y441330D01*
G01X605223Y440190D02*
X605224Y440180D01*
G01X621885Y424131D02*
X621904Y424060D01*
G01D02*
X621943Y423962D01*
G01D02*
X622033Y423825D01*
G01D02*
X622192Y423698D01*
G01D02*
X622405Y423628D01*
G01X619789Y441641D02*
X619792Y441631D01*
G01D02*
X619803Y441590D01*
G01D02*
X619817Y441522D01*
G01D02*
X619833Y441431D01*
G01D02*
X619850Y441319D01*
G01D02*
X619868Y441187D01*
G01D02*
X619886Y441033D01*
G01D02*
X619905Y440858D01*
G01D02*
X619924Y440661D01*
G01X616137Y424519D02*
X616127Y424552D01*
G01D02*
X616111Y424619D01*
G01D02*
X616091Y424717D01*
G01D02*
X616069Y424843D01*
G01D02*
X616046Y424996D01*
G01D02*
X616021Y425178D01*
G01D02*
X615996Y425387D01*
G01D02*
X615971Y425622D01*
G01D02*
X615944Y425885D01*
G01D02*
X615918Y426174D01*
G01D02*
X615891Y426488D01*
G01D02*
X615863Y426830D01*
G01D02*
X615835Y427197D01*
G01D02*
X615806Y427591D01*
G01X619221Y424519D02*
X619211Y424551D01*
G01D02*
X619194Y424619D01*
G01D02*
X619174Y424720D01*
G01D02*
X619151Y424853D01*
G01D02*
X619126Y425018D01*
G01D02*
X619101Y425214D01*
G01D02*
X619074Y425443D01*
G01D02*
X619046Y425704D01*
G01D02*
X619018Y425997D01*
G01D02*
X618988Y426324D01*
G01D02*
X618958Y426684D01*
G01D02*
X618927Y427079D01*
G01D02*
X618896Y427510D01*
G01X613054Y424519D02*
X613044Y424550D01*
G01D02*
X613028Y424616D01*
G01D02*
X613008Y424713D01*
G01D02*
X612986Y424840D01*
G01D02*
X612963Y424994D01*
G01D02*
X612938Y425178D01*
G01D02*
X612913Y425388D01*
G01X610555Y441623D02*
X610564Y441596D01*
G01D02*
X610579Y441533D01*
G01D02*
X610599Y441440D01*
G01D02*
X610620Y441319D01*
G01D02*
X610643Y441170D01*
G01D02*
X610667Y440995D01*
G01D02*
X610691Y440794D01*
G01D02*
X610717Y440566D01*
G01D02*
X610742Y440313D01*
G01D02*
X610769Y440034D01*
G01D02*
X610795Y439730D01*
G01D02*
X610822Y439400D01*
G01D02*
X610850Y439046D01*
G01D02*
X610878Y438666D01*
G01X613639Y441623D02*
X613646Y441598D01*
G01D02*
X613662Y441536D01*
G01D02*
X613681Y441444D01*
G01D02*
X613703Y441322D01*
G01D02*
X613726Y441173D01*
G01D02*
X613750Y440996D01*
G01D02*
X613775Y440793D01*
G01D02*
X613800Y440561D01*
G01D02*
X613827Y440303D01*
G01D02*
X613854Y440017D01*
G01D02*
X613881Y439703D01*
G01D02*
X613909Y439361D01*
G01D02*
X613937Y438991D01*
G01D02*
X613966Y438593D01*
G01X604409Y441654D02*
X604410Y441652D01*
G01D02*
X604417Y441626D01*
G01D02*
X604429Y441575D01*
G01D02*
X604443Y441503D01*
G01D02*
X604458Y441411D01*
G01D02*
X604474Y441302D01*
G01D02*
X604492Y441175D01*
G01D02*
X604509Y441030D01*
G01D02*
X604528Y440866D01*
G01D02*
X604547Y440683D01*
G01D02*
X604567Y440482D01*
G01D02*
X604588Y440261D01*
G01D02*
X604597Y440157D01*
G01X607472Y441623D02*
X607480Y441600D01*
G01D02*
X607494Y441544D01*
G01D02*
X607512Y441459D01*
G01D02*
X607532Y441347D01*
G01D02*
X607554Y441210D01*
G01D02*
X607576Y441050D01*
G01D02*
X607600Y440867D01*
G01D02*
X607623Y440659D01*
G01D02*
X607648Y440429D01*
G01D02*
X607672Y440174D01*
G01D02*
X607698Y439896D01*
G01D02*
X607724Y439593D01*
G01D02*
X607750Y439265D01*
G01D02*
X607777Y438914D01*
G01D02*
X607804Y438538D01*
G01X616722Y441624D02*
X616728Y441604D01*
G01D02*
X616742Y441550D01*
G01D02*
X616760Y441469D01*
G01D02*
X616780Y441362D01*
G01D02*
X616801Y441231D01*
G01D02*
X616823Y441076D01*
G01D02*
X616846Y440897D01*
G01D02*
X616869Y440695D01*
G01D02*
X616894Y440469D01*
G01D02*
X616918Y440220D01*
G01D02*
X616943Y439948D01*
G01D02*
X616969Y439652D01*
G01D02*
X616995Y439331D01*
G01D02*
X617021Y438988D01*
G01D02*
X617048Y438620D01*
G01X606888Y424516D02*
Y424517D01*
G01D02*
X606881Y424541D01*
G01D02*
X606866Y424597D01*
G01D02*
X606848Y424682D01*
G01D02*
X606828Y424792D01*
G01D02*
X606807Y424926D01*
G01D02*
X606784Y425085D01*
G01D02*
X606761Y425267D01*
G01D02*
X606737Y425473D01*
G01D02*
X606713Y425703D01*
G01D02*
X606688Y425957D01*
G01D02*
X606663Y426236D01*
G01D02*
X606637Y426538D01*
G01D02*
X606611Y426863D01*
G01D02*
X606584Y427212D01*
G01D02*
X606557Y427584D01*
G01X604609Y424379D02*
Y424378D01*
G01D02*
X604607Y424397D01*
G01D02*
X604602Y424431D01*
G01D02*
X604597Y424479D01*
G01D02*
X604592Y424539D01*
G01D02*
X604586Y424611D01*
G01D02*
X604580Y424695D01*
G01D02*
X604574Y424792D01*
G01D02*
X604567Y424901D01*
G01D02*
X604561Y425024D01*
G01D02*
X604554Y425160D01*
G01D02*
X604547Y425311D01*
G01D02*
X604540Y425477D01*
G01D02*
X604533Y425658D01*
G01D02*
X604525Y425855D01*
G01D02*
X604520Y425984D01*
G01X621856Y424385D02*
X621853Y424405D01*
G01D02*
X621848Y424442D01*
G01D02*
X621843Y424493D01*
G01D02*
X621836Y424558D01*
G01D02*
X621835Y424570D01*
G01X621331Y441765D02*
X621333Y441748D01*
G01D02*
X621338Y441715D01*
G01D02*
X621343Y441668D01*
G01D02*
X621348Y441608D01*
G01D02*
X621354Y441535D01*
G01D02*
X621360Y441449D01*
G01D02*
X621367Y441350D01*
G01D02*
X621374Y441236D01*
G01D02*
X621380Y441108D01*
G01D02*
X621387Y440966D01*
G01D02*
X621394Y440808D01*
G01D02*
X621402Y440636D01*
G01D02*
X621409Y440448D01*
G01D02*
X621417Y440245D01*
G01D02*
X621425Y440026D01*
G01D02*
X621433Y439793D01*
G01D02*
X621441Y439543D01*
G01D02*
X621448Y439278D01*
G01D02*
X621457Y438996D01*
G01D02*
X621465Y438697D01*
G01D02*
X621474Y438381D01*
G01D02*
X621482Y438047D01*
G01X602901Y441764D02*
X602904Y441747D01*
G01D02*
X602908Y441715D01*
G01D02*
X602913Y441669D01*
G01X609971Y424518D02*
X609961Y424548D01*
G01D02*
X609945Y424613D01*
G01D02*
X609926Y424709D01*
G01D02*
X609904Y424834D01*
G01D02*
X609880Y424988D01*
G01D02*
X609856Y425170D01*
G01D02*
X609830Y425381D01*
G01D02*
X609804Y425620D01*
G01D02*
X609778Y425888D01*
G01D02*
X609750Y426184D01*
G01D02*
X609722Y426509D01*
G01D02*
X609694Y426863D01*
G01D02*
X609665Y427245D01*
G01D02*
X609635Y427657D01*
G01X622811Y431397D02*
X622775Y433089D01*
G01D02*
X622740Y434756D01*
G01X621558Y434781D02*
X621598Y432920D01*
G01D02*
X621617Y431998D01*
G01X621709Y428017D02*
X621717Y427693D01*
G01D02*
X621726Y427381D01*
G01D02*
X621734Y427085D01*
G01D02*
X621742Y426803D01*
G01D02*
X621750Y426535D01*
G01D02*
X621759Y426283D01*
G01D02*
X621767Y426044D01*
G01D02*
X621775Y425821D01*
G01D02*
X621783Y425613D01*
G01D02*
X621790Y425419D01*
G01D02*
X621798Y425241D01*
G01D02*
X621806Y425078D01*
G01D02*
X621813Y424929D01*
G01D02*
X621820Y424795D01*
G01D02*
X621828Y424676D01*
G01D02*
X621835Y424569D01*
G01X622655Y438385D02*
X622647Y438685D01*
G01D02*
X622639Y438972D01*
G01D02*
X622631Y439246D01*
G01D02*
X622623Y439506D01*
G01D02*
X622615Y439753D01*
G01D02*
X622607Y439986D01*
G01D02*
X622600Y440205D01*
G01D02*
X622593Y440411D01*
G01D02*
X622585Y440603D01*
G01D02*
X622578Y440782D01*
G01D02*
X622570Y440947D01*
G01D02*
X622563Y441100D01*
G01D02*
X622556Y441239D01*
G01D02*
X622549Y441367D01*
G01D02*
X622542Y441481D01*
G01D02*
X622535Y441585D01*
G01X622952Y425926D02*
X622944Y426160D01*
G01D02*
X622936Y426412D01*
G01D02*
X622928Y426680D01*
G01D02*
X622919Y426965D01*
G01D02*
X622910Y427266D01*
G01X621615Y429487D02*
X621587Y430282D01*
G01D02*
X621572Y430694D01*
G01D02*
X621527Y431981D01*
G01X620379Y431039D02*
X620408Y430204D01*
G01D02*
X620463Y428672D01*
G01X620332Y432363D02*
X620364Y431472D01*
G01D02*
X620379Y431039D01*
G01X621461Y433783D02*
X621443Y434245D01*
G01D02*
X621425Y434710D01*
G01D02*
X621407Y435178D01*
G01D02*
X621388Y435648D01*
G01D02*
X621368Y436118D01*
G01D02*
X621348Y436587D01*
G01X620513Y427350D02*
X620524Y427055D01*
G01D02*
X620535Y426774D01*
G01D02*
X620546Y426508D01*
G01D02*
X620557Y426257D01*
G01D02*
X620568Y426021D01*
G01D02*
X620578Y425799D01*
G01D02*
X620588Y425593D01*
G01D02*
X620598Y425401D01*
G01D02*
X620607Y425224D01*
G01D02*
X620617Y425063D01*
G01D02*
X620626Y424916D01*
G01D02*
X620634Y424783D01*
G01D02*
X620643Y424665D01*
G01D02*
X620651Y424560D01*
G01X620150Y436952D02*
X620170Y436510D01*
G01D02*
X620189Y436059D01*
G01D02*
X620208Y435602D01*
G01D02*
X620227Y435141D01*
G01D02*
X620246Y434676D01*
G01D02*
X620264Y434210D01*
G01D02*
X620281Y433744D01*
G01D02*
X620298Y433280D01*
G01X621348Y436587D02*
X621326Y437054D01*
G01D02*
X621305Y437516D01*
G01D02*
X621282Y437972D01*
G01D02*
X621259Y438414D01*
G01D02*
X621236Y438837D01*
G01D02*
X621212Y439237D01*
G01D02*
X621189Y439608D01*
G01D02*
X621165Y439948D01*
G01D02*
X621142Y440257D01*
G01D02*
X621120Y440535D01*
G01D02*
X621098Y440785D01*
G01D02*
X621076Y441009D01*
G01D02*
X621054Y441208D01*
G01D02*
X621031Y441385D01*
G01D02*
X621009Y441544D01*
G01D02*
X620986Y441685D01*
G01D02*
X620961Y441811D01*
G01D02*
X620934Y441924D01*
G01D02*
X620902Y442030D01*
G01D02*
X620856Y442142D01*
G01D02*
X620773Y442275D01*
G01D02*
X620613Y442421D01*
G01D02*
X620358Y442514D01*
G01D02*
X620280Y442520D01*
G01X617311Y434336D02*
X617375Y433175D01*
G01D02*
X617443Y431952D01*
G01X615556Y431668D02*
X615486Y432929D01*
G01D02*
X615413Y434254D01*
G01X614222Y434417D02*
X614296Y433102D01*
G01D02*
X614370Y431760D01*
G01X617443Y431952D02*
X617478Y431321D01*
G01D02*
X617515Y430686D01*
G01D02*
X617551Y430056D01*
G01D02*
X617588Y429443D01*
G01D02*
X617624Y428855D01*
G01D02*
X617660Y428301D01*
G01D02*
X617694Y427787D01*
G01X615413Y434254D02*
X615375Y434918D01*
G01D02*
X615338Y435567D01*
G01D02*
X615302Y436193D01*
G01D02*
X615266Y436786D01*
G01D02*
X615231Y437341D01*
G01D02*
X615198Y437860D01*
G01D02*
X615166Y438342D01*
G01X618495Y434270D02*
X618458Y434930D01*
G01D02*
X618422Y435567D01*
G01D02*
X618386Y436181D01*
G01D02*
X618351Y436766D01*
G01D02*
X618317Y437321D01*
G01D02*
X618283Y437844D01*
G01D02*
X618250Y438333D01*
G01X614370Y431760D02*
X614407Y431106D01*
G01D02*
X614443Y430477D01*
G01D02*
X614478Y429880D01*
G01D02*
X614512Y429318D01*
G01D02*
X614544Y428789D01*
G01D02*
X614576Y428292D01*
G01D02*
X614608Y427826D01*
G01X618686Y430862D02*
X618648Y431532D01*
G01D02*
X618609Y432217D01*
G01X611511Y428024D02*
X611544Y427540D01*
G01D02*
X611577Y427093D01*
G01D02*
X611608Y426683D01*
G01D02*
X611639Y426307D01*
G01D02*
X611669Y425965D01*
G01D02*
X611699Y425655D01*
G01D02*
X611728Y425374D01*
G01D02*
X611757Y425123D01*
G01D02*
X611785Y424901D01*
G01D02*
X611814Y424706D01*
G01D02*
X611842Y424536D01*
G01D02*
X611871Y424389D01*
G01D02*
X611902Y424259D01*
G01D02*
X611938Y424141D01*
G01D02*
X611985Y424023D01*
G01D02*
X612063Y423890D01*
G01D02*
X612212Y423741D01*
G01D02*
X612468Y423633D01*
G01D02*
X612576Y423623D01*
G01X612721Y427613D02*
X612692Y428038D01*
G01D02*
X612662Y428490D01*
G01D02*
X612631Y428967D01*
G01D02*
X612601Y429469D01*
G01D02*
X612569Y429996D01*
G01D02*
X612537Y430547D01*
G01D02*
X612504Y431121D01*
G01D02*
X612470Y431719D01*
G01X615806Y427591D02*
X615777Y428011D01*
G01D02*
X615747Y428458D01*
G01D02*
X615717Y428931D01*
G01D02*
X615687Y429428D01*
G01D02*
X615655Y429951D01*
G01D02*
X615623Y430499D01*
G01D02*
X615590Y431071D01*
G01D02*
X615556Y431668D01*
G01X613966Y438593D02*
X613996Y438169D01*
G01D02*
X614026Y437717D01*
G01D02*
X614057Y437239D01*
G01D02*
X614088Y436732D01*
G01D02*
X614120Y436197D01*
G01D02*
X614153Y435633D01*
G01D02*
X614187Y435039D01*
G01D02*
X614222Y434417D01*
G01X618896Y427510D02*
X618863Y427976D01*
G01D02*
X618830Y428480D01*
G01D02*
X618795Y429021D01*
G01D02*
X618760Y429600D01*
G01D02*
X618723Y430215D01*
G01D02*
X618686Y430862D01*
G01X617048Y438620D02*
X617075Y438230D01*
G01D02*
X617103Y437815D01*
G01D02*
X617131Y437379D01*
G01D02*
X617160Y436921D01*
G01D02*
X617189Y436443D01*
G01D02*
X617219Y435944D01*
G01D02*
X617249Y435426D01*
G01D02*
X617279Y434890D01*
G01D02*
X617311Y434336D01*
G01X614608Y427826D02*
X614638Y427391D01*
G01D02*
X614668Y426984D01*
G01D02*
X614698Y426604D01*
G01D02*
X614727Y426252D01*
G01D02*
X614756Y425927D01*
G01D02*
X614785Y425630D01*
G01D02*
X614813Y425359D01*
G01D02*
X614841Y425117D01*
G01D02*
X614869Y424900D01*
G01D02*
X614896Y424709D01*
G01D02*
X614925Y424541D01*
G01D02*
X614954Y424393D01*
G01D02*
X614985Y424263D01*
G01D02*
X615020Y424144D01*
G01D02*
X615067Y424025D01*
G01D02*
X615146Y423891D01*
G01D02*
X615295Y423741D01*
G01D02*
X615552Y423632D01*
G01D02*
X615659Y423622D01*
G01X610878Y438666D02*
X610906Y438261D01*
G01D02*
X610935Y437832D01*
G01D02*
X610964Y437379D01*
G01D02*
X610994Y436902D01*
G01D02*
X611024Y436404D01*
G01D02*
X611055Y435882D01*
G01D02*
X611087Y435339D01*
G01D02*
X611119Y434772D01*
G01D02*
X611152Y434184D01*
G01X618250Y438333D02*
X618218Y438789D01*
G01D02*
X618187Y439211D01*
G01D02*
X618156Y439600D01*
G01D02*
X618126Y439956D01*
G01D02*
X618097Y440281D01*
G01D02*
X618068Y440576D01*
G01D02*
X618040Y440841D01*
G01D02*
X618012Y441078D01*
G01D02*
X617984Y441287D01*
G01D02*
X617957Y441471D01*
G01D02*
X617929Y441633D01*
G01D02*
X617900Y441774D01*
G01D02*
X617869Y441900D01*
G01D02*
X617833Y442015D01*
G01D02*
X617785Y442131D01*
G01D02*
X617703Y442265D01*
G01D02*
X617548Y442412D01*
G01D02*
X617289Y442512D01*
G01D02*
X617200Y442519D01*
G01X615166Y438342D02*
X615135Y438790D01*
G01D02*
X615104Y439204D01*
G01D02*
X615074Y439587D01*
G01D02*
X615044Y439939D01*
G01D02*
X615015Y440261D01*
G01D02*
X614987Y440555D01*
G01D02*
X614958Y440820D01*
G01D02*
X614930Y441058D01*
G01D02*
X614903Y441269D01*
G01D02*
X614875Y441456D01*
G01D02*
X614847Y441621D01*
G01D02*
X614819Y441765D01*
G01D02*
X614787Y441892D01*
G01D02*
X614752Y442008D01*
G01D02*
X614704Y442125D01*
G01D02*
X614624Y442259D01*
G01D02*
X614470Y442407D01*
G01D02*
X614210Y442511D01*
G01D02*
X614117Y442519D01*
G01X617694Y427787D02*
X617727Y427316D01*
G01D02*
X617759Y426888D01*
G01D02*
X617790Y426499D01*
G01D02*
X617820Y426145D01*
G01D02*
X617849Y425826D01*
G01D02*
X617878Y425537D01*
G01D02*
X617906Y425277D01*
G01D02*
X617933Y425045D01*
G01D02*
X617961Y424840D01*
G01D02*
X617988Y424659D01*
G01D02*
X618016Y424500D01*
G01D02*
X618044Y424359D01*
G01D02*
X618076Y424236D01*
G01D02*
X618111Y424122D01*
G01D02*
X618161Y424006D01*
G01D02*
X618243Y423874D01*
G01D02*
X618396Y423730D01*
G01D02*
X618646Y423631D01*
G01D02*
X618743Y423623D01*
G01X612081Y438357D02*
X612050Y438806D01*
G01D02*
X612019Y439222D01*
G01D02*
X611989Y439605D01*
G01D02*
X611959Y439956D01*
G01D02*
X611930Y440278D01*
G01D02*
X611902Y440571D01*
G01D02*
X611873Y440836D01*
G01D02*
X611845Y441073D01*
G01D02*
X611818Y441283D01*
G01D02*
X611790Y441468D01*
G01D02*
X611762Y441631D01*
G01D02*
X611733Y441773D01*
G01D02*
X611702Y441898D01*
G01D02*
X611667Y442013D01*
G01D02*
X611619Y442130D01*
G01D02*
X611537Y442263D01*
G01D02*
X611382Y442411D01*
G01D02*
X611123Y442512D01*
G01D02*
X611033Y442519D01*
G01X621835Y424569D02*
X621842Y424475D01*
G01D02*
X621849Y424392D01*
G01D02*
X621857Y424319D01*
G01D02*
X621865Y424254D01*
G01D02*
X621874Y424194D01*
G01D02*
X621885Y424131D01*
G01X622535Y441585D02*
X622528Y441676D01*
G01D02*
X622520Y441757D01*
G01D02*
X622513Y441830D01*
G01D02*
X622505Y441894D01*
G01D02*
X622496Y441954D01*
G01D02*
X622485Y442013D01*
G01D02*
X622466Y442083D01*
G01D02*
X622427Y442182D01*
G01D02*
X622337Y442318D01*
G01D02*
X622175Y442446D01*
G01D02*
X621956Y442516D01*
G01D02*
X621890Y442520D01*
G01X620651Y424560D02*
X620659Y424467D01*
G01D02*
X620667Y424385D01*
G01D02*
X620675Y424313D01*
G01D02*
X620683Y424248D01*
G01D02*
X620693Y424188D01*
G01D02*
X620705Y424126D01*
G01D02*
X620724Y424056D01*
G01D02*
X620763Y423959D01*
G01D02*
X620853Y423824D01*
G01D02*
X621011Y423698D01*
G01D02*
X621223Y423628D01*
G01X621835Y424570D02*
X621829Y424637D01*
G01D02*
X621822Y424731D01*
G01D02*
X621814Y424840D01*
G01D02*
X621806Y424965D01*
G01D02*
X621797Y425105D01*
G01D02*
X621788Y425261D01*
G01D02*
X621778Y425434D01*
G01D02*
X621769Y425623D01*
G01D02*
X621759Y425828D01*
G01D02*
X621748Y426050D01*
G01D02*
X621738Y426287D01*
G01D02*
X621727Y426540D01*
G01D02*
X621716Y426809D01*
G01D02*
X621704Y427093D01*
G01D02*
X621693Y427393D01*
G01X619924Y440661D02*
X619944Y440440D01*
G01D02*
X619964Y440196D01*
G01D02*
X619984Y439927D01*
G01D02*
X620004Y439632D01*
G01D02*
X620025Y439311D01*
G01D02*
X620046Y438967D01*
G01D02*
X620067Y438599D01*
G01D02*
X620088Y438211D01*
G01D02*
X620109Y437806D01*
G01D02*
X620130Y437385D01*
G01D02*
X620150Y436952D01*
G01X623039Y424379D02*
Y424380D01*
G01D02*
X623035Y424403D01*
G01D02*
X623031Y424443D01*
G01D02*
X623025Y424499D01*
G01D02*
X623019Y424570D01*
G01D02*
X623013Y424657D01*
G01D02*
X623006Y424759D01*
G01D02*
X622998Y424877D01*
G01D02*
X622991Y425011D01*
G01D02*
X622984Y425160D01*
G01D02*
X622976Y425327D01*
G01D02*
X622969Y425509D01*
G01D02*
X622961Y425709D01*
G01D02*
X622952Y425926D01*
G01X612913Y425388D02*
X612887Y425625D01*
G01D02*
X612861Y425889D01*
G01D02*
X612834Y426181D01*
G01D02*
X612806Y426498D01*
G01D02*
X612778Y426843D01*
G01D02*
X612750Y427214D01*
G01D02*
X612721Y427613D01*
G01X611170Y438386D02*
X611195Y438739D01*
G01D02*
X611222Y439111D01*
G01D02*
X611250Y439458D01*
G01D02*
X611276Y439780D01*
G01D02*
X611302Y440076D01*
G01D02*
X611328Y440346D01*
G01D02*
X611353Y440591D01*
G01D02*
X611378Y440810D01*
G01D02*
X611402Y441004D01*
G01D02*
X611425Y441174D01*
G01D02*
X611447Y441319D01*
G01D02*
X611468Y441438D01*
G01D02*
X611487Y441531D01*
G01D02*
X611503Y441595D01*
G01D02*
X611504Y441600D01*
G01X618613Y427856D02*
X618584Y427439D01*
G01D02*
X618555Y427049D01*
G01D02*
X618527Y426687D01*
G01D02*
X618499Y426352D01*
G01D02*
X618472Y426046D01*
G01D02*
X618445Y425768D01*
G01D02*
X618419Y425518D01*
G01D02*
X618394Y425296D01*
G01D02*
X618369Y425100D01*
G01D02*
X618346Y424932D01*
G01D02*
X618323Y424791D01*
G01D02*
X618302Y424676D01*
G01D02*
X618284Y424591D01*
G01D02*
X618270Y424536D01*
G01D02*
X618269Y424531D01*
G01X617327Y438246D02*
X617356Y438655D01*
G01D02*
X617384Y439038D01*
G01D02*
X617411Y439395D01*
G01D02*
X617439Y439727D01*
G01D02*
X617465Y440032D01*
G01D02*
X617491Y440311D01*
G01D02*
X617517Y440563D01*
G01D02*
X617542Y440789D01*
G01D02*
X617567Y440989D01*
G01D02*
X617590Y441163D01*
G01D02*
X617613Y441311D01*
G01D02*
X617634Y441433D01*
G01D02*
X617654Y441528D01*
G01D02*
X617670Y441593D01*
G01D02*
X617671Y441598D01*
G01X612459Y428047D02*
X612410Y427344D01*
G01D02*
X612359Y426681D01*
G01D02*
X612307Y426071D01*
G01D02*
X612253Y425528D01*
G01D02*
X612198Y425072D01*
G01D02*
X612153Y424772D01*
G01X615535Y427929D02*
X615506Y427520D01*
G01D02*
X615478Y427135D01*
G01D02*
X615450Y426775D01*
G01D02*
X615423Y426441D01*
G01D02*
X615396Y426132D01*
G01D02*
X615369Y425849D01*
G01D02*
X615343Y425592D01*
G01D02*
X615318Y425362D01*
G01D02*
X615293Y425158D01*
G01D02*
X615269Y424981D01*
G01D02*
X615246Y424830D01*
G01D02*
X615224Y424707D01*
G01D02*
X615205Y424611D01*
G01D02*
X615189Y424546D01*
G01D02*
X615187Y424541D01*
G01X613071Y438386D02*
X613063Y438278D01*
G01D02*
X613030Y437769D01*
G01D02*
X612995Y437225D01*
G01D02*
X612959Y436646D01*
G01D02*
X612923Y436034D01*
G01D02*
X612885Y435391D01*
G01D02*
X612847Y434720D01*
G01D02*
X612808Y434024D01*
G01D02*
X612769Y433306D01*
G01X616155Y438386D02*
X616141Y438194D01*
G01D02*
X616108Y437687D01*
G01D02*
X616073Y437142D01*
G01D02*
X616037Y436558D01*
G01D02*
X616001Y435941D01*
G01D02*
X615964Y435300D01*
G01D02*
X615927Y434644D01*
G01D02*
X615890Y433983D01*
G01D02*
X615853Y433328D01*
G01X616705Y427756D02*
X616721Y427993D01*
G01D02*
X616754Y428492D01*
G01D02*
X616788Y429029D01*
G01D02*
X616823Y429605D01*
G01D02*
X616859Y430215D01*
G01D02*
X616896Y430851D01*
G01D02*
X616933Y431504D01*
G01D02*
X616970Y432163D01*
G01D02*
X617006Y432819D01*
G01X619239Y438386D02*
X619213Y438006D01*
G01D02*
X619170Y437358D01*
G01D02*
X619130Y436696D01*
G01D02*
X619090Y436026D01*
G01D02*
X619051Y435354D01*
G01X614229Y438032D02*
X614258Y438465D01*
G01D02*
X614287Y438870D01*
G01D02*
X614316Y439247D01*
G01D02*
X614344Y439598D01*
G01D02*
X614372Y439921D01*
G01D02*
X614399Y440216D01*
G01D02*
X614426Y440485D01*
G01D02*
X614452Y440726D01*
G01D02*
X614477Y440940D01*
G01D02*
X614502Y441127D01*
G01D02*
X614525Y441286D01*
G01D02*
X614548Y441417D01*
G01D02*
X614568Y441519D01*
G01D02*
X614585Y441589D01*
G01D02*
X614587Y441596D01*
G01X619778Y427601D02*
X619810Y428074D01*
G01D02*
X619843Y428579D01*
G01D02*
X619877Y429115D01*
G01D02*
X619889Y429320D01*
G01X610538Y427756D02*
X610562Y428111D01*
G01D02*
X610598Y428671D01*
G01D02*
X610636Y429272D01*
G01D02*
X610674Y429907D01*
G01D02*
X610713Y430562D01*
G01D02*
X610750Y431227D01*
G01X613621Y427756D02*
X613654Y428233D01*
G01D02*
X613696Y428902D01*
G01D02*
X613738Y429583D01*
G01D02*
X613779Y430270D01*
G01D02*
X613819Y430958D01*
G01D02*
X613857Y431642D01*
G01D02*
X613931Y432981D01*
G01X621947Y424601D02*
X621954Y424712D01*
G01D02*
X621962Y424835D01*
G01D02*
X621969Y424972D01*
G01D02*
X621976Y425122D01*
G01D02*
X621984Y425285D01*
G01D02*
X621991Y425463D01*
G01D02*
X621999Y425654D01*
G01D02*
X622007Y425859D01*
G01D02*
X622015Y426078D01*
G01D02*
X622022Y426311D01*
G01D02*
X622030Y426558D01*
G01D02*
X622038Y426819D01*
G01D02*
X622046Y427094D01*
G01D02*
X622054Y427382D01*
G01D02*
X622063Y427684D01*
G01D02*
X622070Y427998D01*
G01D02*
X622087Y428665D01*
G01X621241Y441519D02*
X621233Y441396D01*
G01D02*
X621225Y441258D01*
G01D02*
X621217Y441102D01*
G01D02*
X621209Y440928D01*
G01D02*
X621200Y440735D01*
G01D02*
X621192Y440524D01*
G01D02*
X621183Y440292D01*
G01D02*
X621174Y440040D01*
G01D02*
X621169Y439889D01*
G01X620307Y436630D02*
X620353Y437366D01*
G01D02*
X620400Y438085D01*
G01D02*
X620448Y438778D01*
G01D02*
X620498Y439433D01*
G01D02*
X620550Y440039D01*
G01D02*
X620603Y440580D01*
G01D02*
X620657Y441039D01*
G01D02*
X620702Y441340D01*
G01X619889Y429320D02*
X619911Y429683D01*
G01D02*
X619947Y430281D01*
G01D02*
X619983Y430909D01*
G01X614104Y436030D02*
X614136Y436570D01*
G01D02*
X614168Y437085D01*
G01D02*
X614198Y437572D01*
G01D02*
X614229Y438032D01*
G01X611020Y436013D02*
X611050Y436523D01*
G01D02*
X611080Y437012D01*
G01D02*
X611109Y437478D01*
G01D02*
X611138Y437922D01*
G01X612599Y430293D02*
X612554Y429531D01*
G01D02*
X612507Y428780D01*
G01D02*
X612459Y428047D01*
G01X607934Y435970D02*
X607966Y436510D01*
G01D02*
X607998Y437025D01*
G01D02*
X608028Y437514D01*
G01D02*
X608059Y437976D01*
G01X618768Y430328D02*
X618736Y429783D01*
G01D02*
X618705Y429263D01*
G01D02*
X618674Y428769D01*
G01D02*
X618643Y428299D01*
G01D02*
X618613Y427856D01*
G01X617175Y435822D02*
X617207Y436356D01*
G01D02*
X617238Y436866D01*
G01D02*
X617268Y437352D01*
G01D02*
X617298Y437812D01*
G01D02*
X617327Y438246D01*
G01X615685Y430339D02*
X615654Y429810D01*
G01D02*
X615623Y429304D01*
G01D02*
X615593Y428822D01*
G01D02*
X615564Y428363D01*
G01D02*
X615535Y427929D01*
G01X609522Y430396D02*
X609489Y429846D01*
G01D02*
X609458Y429324D01*
G01D02*
X609427Y428828D01*
G01D02*
X609396Y428357D01*
G01D02*
X609367Y427911D01*
G01X620224Y435216D02*
X620263Y435884D01*
G01D02*
X620307Y436630D01*
G01X607869Y434843D02*
X607901Y435406D01*
G01D02*
X607934Y435970D01*
G01X618834Y431484D02*
X618801Y430895D01*
G01D02*
X618768Y430328D01*
G01X619051Y435354D02*
X619013Y434683D01*
G01D02*
X618976Y434019D01*
G01D02*
X618939Y433363D01*
G01D02*
X618904Y432720D01*
G01D02*
X618869Y432093D01*
G01D02*
X618834Y431484D01*
G01X619983Y430909D02*
X620020Y431563D01*
G01D02*
X620058Y432242D01*
G01D02*
X620097Y432942D01*
G01X609573Y431299D02*
X609555Y430972D01*
G01D02*
X609522Y430396D01*
G01X609772Y434861D02*
X609735Y434199D01*
G01D02*
X609624Y432207D01*
G01X610788Y431889D02*
X610925Y434366D01*
G01D02*
X610957Y434935D01*
G01D02*
X610989Y435484D01*
G01D02*
X611020Y436013D01*
G01X617006Y432819D02*
X617076Y434083D01*
G01D02*
X617110Y434685D01*
G01D02*
X617143Y435265D01*
G01D02*
X617175Y435822D01*
G01X615853Y433328D02*
X615783Y432066D01*
G01D02*
X615750Y431468D01*
G01D02*
X615717Y430892D01*
G01D02*
X615685Y430339D01*
G01X613931Y432981D02*
X614003Y434262D01*
G01D02*
X614037Y434874D01*
G01D02*
X614071Y435463D01*
G01D02*
X614104Y436030D01*
G01X612769Y433306D02*
X612686Y431818D01*
G01D02*
X612643Y431057D01*
G01D02*
X612599Y430293D01*
G01X605077Y436243D02*
X605096Y436754D01*
G01D02*
X605115Y437243D01*
G01D02*
X605134Y437707D01*
G01D02*
X605153Y438146D01*
G01X603579Y425934D02*
X603571Y425724D01*
G01D02*
X603563Y425528D01*
G01D02*
X603556Y425348D01*
G01D02*
X603548Y425183D01*
G01D02*
X603541Y425033D01*
G01D02*
X603534Y424900D01*
G01D02*
X603527Y424782D01*
G01D02*
X603520Y424680D01*
G01D02*
X603514Y424592D01*
G01D02*
X603508Y424520D01*
G01D02*
X603502Y424462D01*
G01D02*
X603498Y424418D01*
G01D02*
X603494Y424389D01*
G01D02*
X603493Y424383D01*
G01X603924Y439987D02*
X603932Y440206D01*
G01D02*
X603939Y440409D01*
G01D02*
X603946Y440597D01*
G01D02*
X603954Y440769D01*
G01D02*
X603961Y440927D01*
G01D02*
X603968Y441070D01*
G01D02*
X603974Y441199D01*
G01D02*
X603981Y441315D01*
G01D02*
X603988Y441418D01*
G01D02*
X603994Y441508D01*
G01D02*
X604000Y441585D01*
G01D02*
X604006Y441650D01*
G01D02*
X604011Y441702D01*
G01D02*
X604015Y441740D01*
G01D02*
X604019Y441762D01*
G01D02*
Y441763D01*
G01X602750Y440212D02*
X602741Y439951D01*
G01D02*
X602732Y439670D01*
G01D02*
X602723Y439371D01*
G01X604776Y426370D02*
X604791Y426858D01*
G01D02*
X604819Y427756D01*
G01X603848Y434843D02*
X603830Y434309D01*
G01D02*
X603810Y433647D01*
G01D02*
X603789Y432970D01*
G01D02*
X603769Y432283D01*
G01D02*
X603748Y431589D01*
G01X603900Y439237D02*
X603908Y439503D01*
G01D02*
X603916Y439753D01*
G01D02*
X603924Y439987D01*
G01X621156Y439473D02*
X621146Y439157D01*
G01D02*
X621137Y438821D01*
G01D02*
X621127Y438465D01*
G01D02*
X621117Y438090D01*
G01D02*
X621107Y437696D01*
G01D02*
X621097Y437286D01*
G01D02*
X621077Y436421D01*
G01X602438Y427207D02*
X602425Y426761D01*
G01D02*
X602412Y426340D01*
G01D02*
X602402Y426046D01*
G01X604921Y431299D02*
X604946Y432174D01*
G01D02*
X604965Y432792D01*
G01D02*
X604983Y433402D01*
G01D02*
X605000Y433936D01*
G01X603689Y429519D02*
X603670Y428851D01*
G01D02*
X603651Y428203D01*
G01D02*
X603637Y427756D01*
G01X622298Y438069D02*
X622314Y438664D01*
G01D02*
X622322Y438940D01*
G01D02*
X622329Y439202D01*
G01D02*
X622337Y439450D01*
G01D02*
X622344Y439684D01*
G01D02*
X622351Y439905D01*
G01D02*
X622358Y440113D01*
G01D02*
X622365Y440307D01*
G01D02*
X622372Y440489D01*
G01D02*
X622379Y440659D01*
G01D02*
X622385Y440815D01*
G01D02*
X622392Y440959D01*
G01D02*
X622399Y441091D01*
G01D02*
X622405Y441210D01*
G01D02*
X622411Y441317D01*
G01D02*
X622417Y441413D01*
G01D02*
X622423Y441497D01*
G01D02*
X622428Y441570D01*
G01D02*
X622434Y441633D01*
G01D02*
X622439Y441684D01*
G01D02*
X622443Y441724D01*
G01D02*
X622447Y441754D01*
G01X602464Y428161D02*
X602451Y427675D01*
G01D02*
X602438Y427207D01*
G01X602685Y437986D02*
X602675Y437595D01*
G01D02*
X602665Y437186D01*
G01D02*
X602645Y436320D01*
G01X620919Y429208D02*
X620902Y428474D01*
G01D02*
X620893Y428128D01*
G01D02*
X620884Y427797D01*
G01D02*
X620876Y427481D01*
G01D02*
X620867Y427180D01*
G01D02*
X620859Y426893D01*
G01D02*
X620851Y426621D01*
G01D02*
X620843Y426365D01*
G01D02*
X620834Y426123D01*
G01D02*
X620826Y425897D01*
G01D02*
X620819Y425686D01*
G01D02*
X620811Y425491D01*
G01D02*
X620803Y425312D01*
G01D02*
X620796Y425149D01*
G01D02*
X620788Y425002D01*
G01D02*
X620781Y424870D01*
G01D02*
X620774Y424754D01*
G01D02*
X620767Y424653D01*
G01D02*
X620761Y424567D01*
G01D02*
X620754Y424497D01*
G01D02*
X620749Y424442D01*
G01D02*
X620744Y424402D01*
G01D02*
X620741Y424379D01*
G01X603650Y428374D02*
X603662Y428833D01*
G01D02*
X603673Y429300D01*
G01D02*
X603684Y429773D01*
G01D02*
X603718Y431299D01*
G01X603841Y436954D02*
X603858Y437680D01*
G01D02*
X603867Y438022D01*
G01X602536Y431293D02*
X602513Y430226D01*
G01D02*
X602501Y429698D01*
G01D02*
X602489Y429176D01*
G01D02*
X602476Y428663D01*
G01D02*
X602464Y428161D01*
G01X604263Y436852D02*
X604252Y437311D01*
G01D02*
X604241Y437749D01*
G01D02*
X604231Y438162D01*
G01D02*
X604211Y438911D01*
G01X603294Y427434D02*
X603303Y427134D01*
G01D02*
X603311Y426850D01*
G01X604211Y438911D02*
X604201Y439247D01*
G01D02*
X604192Y439559D01*
G01D02*
X604182Y439849D01*
G01D02*
X604172Y440157D01*
G01X602994Y440055D02*
X603002Y439823D01*
G01D02*
X603010Y439575D01*
G01D02*
X603018Y439313D01*
G01D02*
X603026Y439035D01*
G01D02*
X603034Y438742D01*
G01X604520Y425984D02*
X604510Y426299D01*
G01D02*
X604502Y426547D01*
G01D02*
X604494Y426813D01*
G01X603339Y425984D02*
X603343Y425861D01*
G01D02*
X603351Y425650D01*
G01D02*
X603359Y425454D01*
G01D02*
X603367Y425272D01*
G01D02*
X603374Y425105D01*
G01D02*
X603382Y424953D01*
G01D02*
X603390Y424816D01*
G01D02*
X603397Y424693D01*
G01D02*
X603404Y424583D01*
G01D02*
X603411Y424486D01*
G01D02*
X603419Y424401D01*
G01D02*
X603426Y424326D01*
G01D02*
X603434Y424260D01*
G01D02*
X603443Y424199D01*
G01D02*
X603454Y424138D01*
G01D02*
X603472Y424066D01*
G01D02*
X603511Y423966D01*
G01D02*
X603599Y423830D01*
G01D02*
X603752Y423703D01*
G01D02*
X603963Y423629D01*
G01D02*
X604051Y423622D01*
G01X604172Y440157D02*
X604165Y440363D01*
G01D02*
X604156Y440589D01*
G01D02*
X604147Y440794D01*
G01D02*
X604139Y440981D01*
G01D02*
X604131Y441149D01*
G01D02*
X604123Y441298D01*
G01D02*
X604115Y441431D01*
G01D02*
X604107Y441548D01*
G01D02*
X604100Y441650D01*
G01D02*
X604092Y441739D01*
G01D02*
X604085Y441816D01*
G01D02*
X604076Y441884D01*
G01D02*
X604068Y441945D01*
G01D02*
X604056Y442006D01*
G01D02*
X604038Y442078D01*
G01D02*
X603997Y442181D01*
G01D02*
X603904Y442321D01*
G01D02*
X603742Y442447D01*
G01D02*
X603526Y442515D01*
G01D02*
X603460Y442519D01*
G01X612470Y431719D02*
X612400Y432976D01*
G01D02*
X612327Y434287D01*
G01X611152Y434184D02*
X611221Y432945D01*
G01D02*
X611293Y431641D01*
G01X609371Y432001D02*
X609298Y433327D01*
G01D02*
X609261Y433993D01*
G01D02*
X609224Y434648D01*
G01D02*
X609188Y435282D01*
G01D02*
X609153Y435887D01*
G01D02*
X609119Y436460D01*
G01D02*
X609087Y437000D01*
G01D02*
X609054Y437509D01*
G01D02*
X609023Y437989D01*
G01D02*
X608996Y438386D01*
G01X608070Y434167D02*
X608135Y432989D01*
G01D02*
X608204Y431750D01*
G01X605109Y431971D02*
X605144Y431347D01*
G01D02*
X605178Y430744D01*
G01X612327Y434287D02*
X612291Y434943D01*
G01D02*
X612254Y435585D01*
G01D02*
X612218Y436206D01*
G01D02*
X612182Y436797D01*
G01D02*
X612148Y437353D01*
G01D02*
X612114Y437873D01*
G01D02*
X612081Y438357D01*
G01X608204Y431750D02*
X608240Y431113D01*
G01D02*
X608277Y430471D01*
G01D02*
X608314Y429836D01*
G01D02*
X608352Y429217D01*
G01D02*
X608389Y428626D01*
G01D02*
X608425Y428070D01*
G01X606158Y434344D02*
X606123Y434969D01*
G01D02*
X606087Y435597D01*
G01D02*
X606050Y436225D01*
G01D02*
X606013Y436849D01*
G01D02*
X605974Y437464D01*
G01D02*
X605944Y437926D01*
G01X611293Y431641D02*
X611330Y430984D01*
G01D02*
X611368Y430337D01*
G01D02*
X611405Y429710D01*
G01D02*
X611441Y429111D01*
G01D02*
X611476Y428548D01*
G01D02*
X611511Y428024D01*
G01X604881Y436016D02*
X604922Y435324D01*
G01D02*
X604961Y434633D01*
G01D02*
X604999Y433949D01*
G01X605212Y430164D02*
X605245Y429609D01*
G01D02*
X605277Y429080D01*
G01D02*
X605309Y428576D01*
G01D02*
X605340Y428100D01*
G01X604764Y437904D02*
X604798Y437381D01*
G01D02*
X604841Y436704D01*
G01D02*
X604881Y436016D01*
G01X605363Y427756D02*
X605370Y427652D01*
G01D02*
X605400Y427232D01*
G01X608425Y428070D02*
X608460Y427557D01*
G01D02*
X608494Y427091D01*
G01D02*
X608526Y426669D01*
G01D02*
X608557Y426288D01*
G01D02*
X608588Y425944D01*
G01D02*
X608618Y425634D01*
G01D02*
X608647Y425357D01*
G01D02*
X608675Y425110D01*
G01D02*
X608704Y424892D01*
G01D02*
X608731Y424701D01*
G01D02*
X608759Y424534D01*
G01D02*
X608788Y424388D01*
G01D02*
X608819Y424259D01*
G01D02*
X608854Y424141D01*
G01D02*
X608901Y424024D01*
G01D02*
X608979Y423891D01*
G01D02*
X609128Y423741D01*
G01D02*
X609384Y423632D01*
G01D02*
X609493Y423622D01*
G01X609635Y427657D02*
X609605Y428099D01*
G01D02*
X609574Y428570D01*
G01D02*
X609542Y429070D01*
G01D02*
X609509Y429600D01*
G01D02*
X609476Y430159D01*
G01D02*
X609442Y430746D01*
G01D02*
X609407Y431361D01*
G01D02*
X609371Y432001D01*
G01X607804Y438538D02*
X607831Y438138D01*
G01D02*
X607859Y437715D01*
G01D02*
X607888Y437270D01*
G01D02*
X607917Y436802D01*
G01D02*
X607947Y436313D01*
G01D02*
X607977Y435805D01*
G01D02*
X608007Y435277D01*
G01D02*
X608038Y434731D01*
G01D02*
X608070Y434167D01*
G01X606557Y427584D02*
X606530Y427980D01*
G01D02*
X606502Y428399D01*
G01D02*
X606474Y428842D01*
G01D02*
X606444Y429306D01*
G01D02*
X606415Y429793D01*
G01D02*
X606385Y430301D01*
G01D02*
X606355Y430829D01*
G01D02*
X606324Y431376D01*
G01D02*
X606292Y431941D01*
G01X605898Y438615D02*
X605871Y438997D01*
G01D02*
X605845Y439354D01*
G01D02*
X605819Y439685D01*
G01D02*
X605794Y439992D01*
G01D02*
X605770Y440274D01*
G01D02*
X605747Y440532D01*
G01D02*
X605724Y440767D01*
G01D02*
X605702Y440980D01*
G01D02*
X605680Y441171D01*
G01D02*
X605659Y441343D01*
G01D02*
X605638Y441496D01*
G01D02*
X605617Y441632D01*
G01D02*
X605595Y441754D01*
G01D02*
X605573Y441863D01*
G01D02*
X605548Y441961D01*
G01D02*
X605517Y442057D01*
G01D02*
X605472Y442162D01*
G01D02*
X605388Y442291D01*
G01D02*
X605227Y442430D01*
G01D02*
X604980Y442515D01*
G01D02*
X604911Y442519D01*
G01X608963Y438861D02*
X608933Y439256D01*
G01D02*
X608904Y439624D01*
G01D02*
X608876Y439965D01*
G01D02*
X608847Y440279D01*
G01D02*
X608819Y440566D01*
G01D02*
X608791Y440827D01*
G01D02*
X608763Y441061D01*
G01D02*
X608736Y441270D01*
G01D02*
X608709Y441456D01*
G01D02*
X608681Y441620D01*
G01D02*
X608652Y441765D01*
G01D02*
X608621Y441892D01*
G01D02*
X608585Y442009D01*
G01D02*
X608537Y442127D01*
G01D02*
X608455Y442262D01*
G01D02*
X608299Y442410D01*
G01D02*
X608039Y442511D01*
G01D02*
X607950Y442518D01*
G01X605400Y427232D02*
X605430Y426840D01*
G01D02*
X605459Y426475D01*
G01D02*
X605488Y426137D01*
G01X604597Y440157D02*
X604609Y440020D01*
G01D02*
X604630Y439758D01*
G01D02*
X604653Y439476D01*
G01D02*
X604676Y439173D01*
G01X605488Y426137D02*
X605516Y425826D01*
G01D02*
X605544Y425543D01*
G01D02*
X605572Y425287D01*
G01D02*
X605599Y425057D01*
G01D02*
X605626Y424853D01*
G01D02*
X605653Y424672D01*
G01D02*
X605680Y424513D01*
G01D02*
X605709Y424372D01*
G01D02*
X605739Y424246D01*
G01D02*
X605775Y424130D01*
G01D02*
X605823Y424013D01*
G01D02*
X605904Y423880D01*
G01D02*
X606057Y423732D01*
G01D02*
X606311Y423630D01*
G01D02*
X606409Y423622D01*
G01X602913Y441669D02*
X602919Y441611D01*
G01D02*
X602924Y441540D01*
G01D02*
X602930Y441456D01*
G01D02*
X602937Y441359D01*
G01D02*
X602943Y441250D01*
G01D02*
X602950Y441126D01*
G01D02*
X602957Y440986D01*
G01D02*
X602964Y440831D01*
G01D02*
X602971Y440661D01*
G01D02*
X602979Y440474D01*
G01D02*
X602983Y440354D01*
G01X612153Y424771D02*
X612143Y424715D01*
G01D02*
X612125Y424626D01*
G01D02*
X612110Y424562D01*
G01D02*
X612099Y424524D01*
G01D02*
X612096Y424517D01*
G01X620702Y441342D02*
X620713Y441407D01*
G01D02*
X620731Y441502D01*
G01D02*
X620748Y441572D01*
G01D02*
X620759Y441617D01*
G01D02*
X620763Y441629D01*
G01X603493Y424383D02*
X603492Y424376D01*
G01D02*
X603493Y424384D01*
G01D02*
X603505Y424421D01*
G01D02*
X603540Y424501D01*
G01D02*
X603623Y424618D01*
G01D02*
X603778Y424735D01*
G01D02*
X603992Y424800D01*
G01D02*
X604051Y424803D01*
G01X622447Y441754D02*
X622449Y441766D01*
G01D02*
X622448Y441760D01*
G01D02*
X622439Y441728D01*
G01D02*
X622409Y441656D01*
G01D02*
X622331Y441540D01*
G01D02*
X622182Y441417D01*
G01D02*
X621969Y441344D01*
G01D02*
X621890Y441339D01*
G01X613319Y424595D02*
X613365Y424900D01*
G01D02*
X613418Y425331D01*
G01D02*
X613468Y425825D01*
G01D02*
X613517Y426371D01*
G01D02*
X613564Y426961D01*
G01D02*
X613609Y427584D01*
G01D02*
X613621Y427756D01*
G01X619535Y441509D02*
X619492Y441221D01*
G01D02*
X619441Y440805D01*
G01D02*
X619393Y440329D01*
G01D02*
X619345Y439802D01*
G01D02*
X619300Y439235D01*
G01D02*
X619256Y438633D01*
G01D02*
X619239Y438386D01*
G01X602834Y441800D02*
X602826Y441716D01*
G01D02*
X602818Y441619D01*
G01D02*
X602810Y441506D01*
G01X604139Y440980D02*
X604123Y440794D01*
G01D02*
X604103Y440532D01*
G01D02*
X604082Y440240D01*
G01X606273Y427756D02*
X606247Y427395D01*
G01D02*
X606220Y427024D01*
G01D02*
X606193Y426677D01*
G01D02*
X606166Y426354D01*
G01D02*
X606139Y426057D01*
G01D02*
X606113Y425785D01*
G01D02*
X606088Y425538D01*
G01D02*
X606063Y425317D01*
G01D02*
X606039Y425122D01*
G01D02*
X606016Y424954D01*
G01D02*
X605993Y424811D01*
G01D02*
X605972Y424693D01*
G01D02*
X605954Y424604D01*
G01D02*
X605938Y424543D01*
G01D02*
X605937Y424539D01*
G01X605264Y440227D02*
X605282Y440480D01*
G01D02*
X605300Y440707D01*
G01D02*
X605317Y440911D01*
G01D02*
X605334Y441089D01*
G01D02*
X605351Y441244D01*
G01D02*
X605367Y441375D01*
G01D02*
X605382Y441483D01*
G01D02*
X605396Y441566D01*
G01D02*
X605407Y441626D01*
G01D02*
X605415Y441659D01*
G01D02*
X605416Y441661D01*
G01X609367Y427911D02*
X609337Y427491D01*
G01D02*
X609308Y427096D01*
G01D02*
X609280Y426728D01*
G01D02*
X609252Y426389D01*
G01D02*
X609224Y426077D01*
G01D02*
X609197Y425794D01*
G01D02*
X609171Y425539D01*
G01D02*
X609146Y425314D01*
G01D02*
X609121Y425116D01*
G01D02*
X609098Y424946D01*
G01D02*
X609075Y424804D01*
G01D02*
X609054Y424687D01*
G01D02*
X609035Y424598D01*
G01D02*
X609020Y424540D01*
G01D02*
X609019Y424535D01*
G01X609988Y438386D02*
X609977Y438230D01*
G01D02*
X609945Y437754D01*
G01D02*
X609913Y437243D01*
G01D02*
X609879Y436699D01*
G01D02*
X609844Y436119D01*
G01D02*
X609809Y435504D01*
G01D02*
X609772Y434861D01*
G01X608059Y437976D02*
X608088Y438411D01*
G01D02*
X608117Y438819D01*
G01D02*
X608146Y439200D01*
G01D02*
X608174Y439554D01*
G01D02*
X608202Y439881D01*
G01D02*
X608229Y440181D01*
G01D02*
X608256Y440455D01*
G01D02*
X608282Y440702D01*
G01D02*
X608308Y440921D01*
G01D02*
X608333Y441113D01*
G01D02*
X608357Y441276D01*
G01D02*
X608380Y441410D01*
G01D02*
X608401Y441515D01*
G01D02*
X608418Y441587D01*
G01D02*
X608419Y441592D01*
G01X606905Y438386D02*
X606879Y438002D01*
G01D02*
X606844Y437463D01*
G01D02*
X606807Y436883D01*
G01D02*
X606770Y436268D01*
G01D02*
X606733Y435626D01*
G01D02*
X606695Y434966D01*
G01X607455Y427756D02*
X607482Y428155D01*
G01D02*
X607515Y428659D01*
G01D02*
X607548Y429198D01*
G01D02*
X607583Y429772D01*
G01D02*
X607619Y430376D01*
G01D02*
X607655Y431004D01*
G01X604696Y424568D02*
X604703Y424674D01*
G01D02*
X604711Y424795D01*
G01D02*
X604718Y424930D01*
G01D02*
X604726Y425083D01*
G01D02*
X604734Y425252D01*
G01D02*
X604742Y425441D01*
G01D02*
X604750Y425650D01*
G01D02*
X604763Y425984D01*
G01X604082Y440240D02*
X604062Y439916D01*
G01D02*
X604041Y439561D01*
G01D02*
X604020Y439172D01*
G01X606422Y430116D02*
X606392Y429607D01*
G01D02*
X606362Y429120D01*
G01D02*
X606333Y428654D01*
G01D02*
X606304Y428211D01*
G01X604019Y441763D02*
X604012Y441737D01*
G01D02*
X603983Y441663D01*
G01D02*
X603902Y441540D01*
G01D02*
X603753Y441417D01*
G01D02*
X603544Y441344D01*
G01D02*
X603460Y441338D01*
G01X606517Y431776D02*
X606485Y431200D01*
G01D02*
X606453Y430647D01*
G01D02*
X606422Y430116D01*
G01X606695Y434966D02*
X606657Y434301D01*
G01D02*
X606551Y432375D01*
G01X602802Y441377D02*
X602794Y441230D01*
G01D02*
X602785Y441065D01*
G01D02*
X602777Y440881D01*
G01X605193Y438985D02*
X605209Y439308D01*
G01D02*
X605228Y439641D01*
G01D02*
X605246Y439947D01*
G01X604020Y439172D02*
X603999Y438751D01*
G01D02*
X603982Y438386D01*
G01X603957Y437812D02*
X603936Y437296D01*
G01D02*
X603915Y436750D01*
G01D02*
X603894Y436177D01*
G01D02*
X603872Y435577D01*
G01D02*
X603848Y434843D01*
G01X618269Y424531D02*
X618264Y424517D01*
G01D02*
X618276Y424542D01*
G01D02*
X618327Y424616D01*
G01D02*
X618452Y424722D01*
G01D02*
X618668Y424799D01*
G01D02*
X618743Y424804D01*
G01X615187Y424541D02*
X615180Y424517D01*
G01D02*
X615188Y424533D01*
G01D02*
X615238Y424609D01*
G01D02*
X615374Y424725D01*
G01D02*
X615604Y424801D01*
G01D02*
X615659Y424804D01*
G01X617671Y441598D02*
X617679Y441624D01*
G01D02*
X617673Y441611D01*
G01D02*
X617630Y441542D01*
G01D02*
X617506Y441429D01*
G01D02*
X617280Y441344D01*
G01D02*
X617200Y441338D01*
G01X614587Y441596D02*
X614595Y441623D01*
G01D02*
X614589Y441611D01*
G01D02*
X614545Y441541D01*
G01D02*
X614419Y441426D01*
G01D02*
X614192Y441343D01*
G01D02*
X614117Y441337D01*
G01X621890Y424114D02*
X621896Y424140D01*
G01D02*
X621908Y424202D01*
G01D02*
X621917Y424266D01*
G01D02*
X621925Y424335D01*
G01D02*
X621932Y424413D01*
G01D02*
X621940Y424502D01*
G01D02*
X621947Y424601D01*
G01X621319Y424803D02*
X621381Y424797D01*
G01D02*
X621587Y424727D01*
G01D02*
X621736Y424608D01*
G01D02*
X621819Y424486D01*
G01D02*
X621849Y424411D01*
G01D02*
X621856Y424385D01*
G01X622494Y424804D02*
X622564Y424797D01*
G01D02*
X622772Y424725D01*
G01D02*
X622922Y424603D01*
G01D02*
X623003Y424479D01*
G01D02*
X623032Y424405D01*
G01D02*
X623039Y424379D01*
G01X606409Y424803D02*
X606488Y424797D01*
G01D02*
X606711Y424715D01*
G01D02*
X606835Y424604D01*
G01D02*
X606880Y424534D01*
G01D02*
X606888Y424516D01*
G01X604051Y424803D02*
X604132Y424797D01*
G01D02*
X604340Y424726D01*
G01D02*
X604490Y424604D01*
G01D02*
X604572Y424480D01*
G01D02*
X604602Y424405D01*
G01D02*
X604609Y424379D01*
G01X614117Y441337D02*
X614039Y441343D01*
G01D02*
X613822Y441422D01*
G01D02*
X613698Y441529D01*
G01D02*
X613648Y441602D01*
G01D02*
X613639Y441623D01*
G01X618743Y424804D02*
X618820Y424799D01*
G01D02*
X619044Y424716D01*
G01D02*
X619169Y424603D01*
G01D02*
X619214Y424533D01*
G01D02*
X619221Y424519D01*
G01X615659Y424804D02*
X615735Y424798D01*
G01D02*
X615961Y424714D01*
G01D02*
X616087Y424601D01*
G01D02*
X616131Y424532D01*
G01D02*
X616137Y424519D01*
G01X612576Y424804D02*
X612651Y424799D01*
G01D02*
X612876Y424716D01*
G01D02*
X613002Y424603D01*
G01D02*
X613047Y424533D01*
G01D02*
X613054Y424519D01*
G01X609493Y424804D02*
X609568Y424798D01*
G01D02*
X609792Y424716D01*
G01D02*
X609919Y424603D01*
G01D02*
X609964Y424533D01*
G01D02*
X609971Y424518D01*
G01X607950Y441337D02*
X607882Y441342D01*
G01D02*
X607655Y441422D01*
G01D02*
X607528Y441533D01*
G01D02*
X607481Y441605D01*
G01D02*
X607472Y441623D01*
G01X603460Y441338D02*
X603392Y441342D01*
G01D02*
X603186Y441407D01*
G01D02*
X603035Y441520D01*
G01D02*
X602947Y441645D01*
G01D02*
X602911Y441727D01*
G01D02*
X602902Y441760D01*
G01D02*
X602901Y441764D01*
G01X617200Y441338D02*
X617136Y441342D01*
G01D02*
X616911Y441419D01*
G01D02*
X616781Y441530D01*
G01D02*
X616732Y441602D01*
G01D02*
X616722Y441624D01*
G01X621890Y441339D02*
X621825Y441343D01*
G01D02*
X621613Y441409D01*
G01D02*
X621458Y441528D01*
G01D02*
X621372Y441653D01*
G01D02*
X621340Y441731D01*
G01D02*
X621331Y441762D01*
G01D02*
Y441765D01*
G01X620280Y441339D02*
X620220Y441342D01*
G01D02*
X619995Y441416D01*
G01D02*
X619858Y441530D01*
G01D02*
X619803Y441612D01*
G01D02*
X619789Y441641D01*
G01X611033Y441338D02*
X610976Y441341D01*
G01D02*
X610748Y441417D01*
G01D02*
X610613Y441531D01*
G01D02*
X610563Y441605D01*
G01D02*
X610555Y441623D01*
G01X604911Y441338D02*
X604861Y441340D01*
G01D02*
X604642Y441406D01*
G01D02*
X604497Y441518D01*
G01D02*
X604432Y441607D01*
G01D02*
X604411Y441649D01*
G01D02*
X604409Y441654D01*
G01X612096Y424517D02*
X612097Y424518D01*
G01D02*
X612114Y424551D01*
G01D02*
X612172Y424630D01*
G01D02*
X612308Y424735D01*
G01D02*
X612524Y424802D01*
G01D02*
X612576Y424804D01*
G01X620763Y441629D02*
X620764Y441631D01*
G01D02*
X620753Y441607D01*
G01D02*
X620705Y441535D01*
G01D02*
X620579Y441425D01*
G01D02*
X620359Y441344D01*
G01D02*
X620280Y441339D01*
G01X609019Y424535D02*
X609013Y424516D01*
G01D02*
X609021Y424534D01*
G01D02*
X609067Y424604D01*
G01D02*
X609185Y424711D01*
G01D02*
X609402Y424796D01*
G01D02*
X609492Y424804D01*
G01X605937Y424539D02*
X605930Y424517D01*
G01D02*
X605939Y424535D01*
G01D02*
X605988Y424609D01*
G01D02*
X606121Y424723D01*
G01D02*
X606349Y424800D01*
G01D02*
X606409Y424803D01*
G01X611504Y441600D02*
X611512Y441624D01*
G01D02*
X611506Y441610D01*
G01D02*
X611462Y441542D01*
G01D02*
X611340Y441430D01*
G01D02*
X611115Y441344D01*
G01D02*
X611033Y441338D01*
G01X608419Y441592D02*
X608428Y441622D01*
G01D02*
X608423Y441610D01*
G01D02*
X608378Y441539D01*
G01D02*
X608248Y441423D01*
G01D02*
X608020Y441342D01*
G01D02*
X607950Y441337D01*
G01X603460Y442519D02*
X603380Y442513D01*
G01D02*
X603170Y442443D01*
G01D02*
X603013Y442316D01*
G01D02*
X602920Y442176D01*
G01D02*
X602881Y442072D01*
G01D02*
X602863Y442000D01*
G01D02*
X602852Y441937D01*
G01D02*
X602842Y441872D01*
G01D02*
X602834Y441800D01*
G01X621890Y442520D02*
X621807Y442514D01*
G01D02*
X621594Y442441D01*
G01D02*
X621437Y442311D01*
G01D02*
X621348Y442170D01*
G01D02*
X621309Y442069D01*
G01D02*
X621292Y441998D01*
G01D02*
X621281Y441936D01*
G01D02*
X621272Y441872D01*
G01D02*
X621264Y441802D01*
G01D02*
X621256Y441720D01*
G01D02*
X621248Y441627D01*
G01D02*
X621241Y441519D01*
G01X620280Y442520D02*
X620192Y442513D01*
G01D02*
X619949Y442422D01*
G01D02*
X619795Y442286D01*
G01D02*
X619712Y442161D01*
G01D02*
X619664Y442054D01*
G01D02*
X619630Y441953D01*
G01D02*
X619602Y441847D01*
G01D02*
X619575Y441730D01*
G01D02*
X619550Y441598D01*
G01D02*
X619535Y441510D01*
G01X604911Y442519D02*
X604822Y442512D01*
G01D02*
X604576Y442419D01*
G01D02*
X604421Y442274D01*
G01D02*
X604341Y442143D01*
G01D02*
X604298Y442035D01*
G01D02*
X604269Y441934D01*
G01D02*
X604245Y441828D01*
G01D02*
X604224Y441709D01*
G01D02*
X604203Y441573D01*
G01D02*
X604183Y441416D01*
G01D02*
X604163Y441234D01*
G01D02*
X604143Y441028D01*
G01D02*
X604139Y440980D01*
G01X614117Y442519D02*
X614018Y442510D01*
G01D02*
X613767Y442410D01*
G01D02*
X613613Y442264D01*
G01D02*
X613532Y442131D01*
G01D02*
X613483Y442013D01*
G01D02*
X613448Y441897D01*
G01D02*
X613417Y441771D01*
G01D02*
X613388Y441628D01*
G01D02*
X613360Y441466D01*
G01D02*
X613333Y441282D01*
G01D02*
X613306Y441074D01*
G01D02*
X613278Y440839D01*
G01D02*
X613249Y440576D01*
G01D02*
X613220Y440280D01*
G01D02*
X613191Y439951D01*
G01D02*
X613160Y439587D01*
G01D02*
X613129Y439187D01*
G01D02*
X613096Y438750D01*
G01D02*
X613071Y438386D01*
G01X611033Y442519D02*
X610929Y442509D01*
G01D02*
X610672Y442402D01*
G01D02*
X610520Y442251D01*
G01D02*
X610441Y442114D01*
G01D02*
X610393Y441993D01*
G01D02*
X610357Y441871D01*
G01D02*
X610326Y441738D01*
G01D02*
X610297Y441587D01*
G01D02*
X610269Y441416D01*
G01D02*
X610241Y441220D01*
G01D02*
X610213Y441000D01*
G01D02*
X610185Y440752D01*
G01D02*
X610156Y440476D01*
G01D02*
X610127Y440172D01*
G01D02*
X610098Y439839D01*
G01D02*
X610068Y439480D01*
G01D02*
X610038Y439092D01*
G01D02*
X610008Y438676D01*
G01D02*
X609988Y438386D01*
G01X617200Y442519D02*
X617092Y442509D01*
G01D02*
X616835Y442400D01*
G01D02*
X616686Y442250D01*
G01D02*
X616608Y442116D01*
G01D02*
X616562Y441998D01*
G01D02*
X616527Y441880D01*
G01D02*
X616496Y441751D01*
G01D02*
X616467Y441604D01*
G01D02*
X616439Y441436D01*
G01D02*
X616411Y441244D01*
G01D02*
X616383Y441027D01*
G01D02*
X616355Y440781D01*
G01D02*
X616326Y440506D01*
G01D02*
X616296Y440200D01*
G01D02*
X616267Y439865D01*
G01D02*
X616237Y439498D01*
G01D02*
X616206Y439098D01*
G01D02*
X616174Y438663D01*
G01D02*
X616155Y438386D01*
G01X607951Y442518D02*
X607840Y442508D01*
G01D02*
X607583Y442397D01*
G01D02*
X607434Y442247D01*
G01D02*
X607357Y442112D01*
G01D02*
X607310Y441993D01*
G01D02*
X607274Y441872D01*
G01D02*
X607243Y441739D01*
G01D02*
X607214Y441586D01*
G01D02*
X607185Y441412D01*
G01D02*
X607157Y441212D01*
G01D02*
X607128Y440983D01*
G01D02*
X607099Y440726D01*
G01D02*
X607069Y440438D01*
G01D02*
X607039Y440119D01*
G01D02*
X607009Y439768D01*
G01D02*
X606978Y439381D01*
G01D02*
X606945Y438959D01*
G01D02*
X606913Y438500D01*
G01D02*
X606905Y438386D01*
G01X604051Y423622D02*
X604116Y423626D01*
G01D02*
X604331Y423693D01*
G01D02*
X604493Y423819D01*
G01D02*
X604587Y423958D01*
G01D02*
X604628Y424061D01*
G01D02*
X604646Y424134D01*
G01D02*
X604658Y424194D01*
G01D02*
X604667Y424254D01*
G01D02*
X604674Y424318D01*
G01D02*
X604681Y424391D01*
G01D02*
X604689Y424474D01*
G01D02*
X604696Y424568D01*
G01X618743Y423623D02*
X618818Y423628D01*
G01D02*
X619078Y423723D01*
G01D02*
X619243Y423874D01*
G01D02*
X619330Y424015D01*
G01D02*
X619380Y424141D01*
G01D02*
X619417Y424265D01*
G01D02*
X619449Y424399D01*
G01D02*
X619478Y424553D01*
G01D02*
X619507Y424729D01*
G01D02*
X619536Y424931D01*
G01D02*
X619565Y425161D01*
G01D02*
X619594Y425420D01*
G01D02*
X619624Y425707D01*
G01D02*
X619654Y426024D01*
G01D02*
X619684Y426372D01*
G01D02*
X619715Y426750D01*
G01D02*
X619746Y427160D01*
G01D02*
X619778Y427601D01*
G01X609492Y423622D02*
X609574Y423628D01*
G01D02*
X609831Y423724D01*
G01D02*
X609993Y423874D01*
G01D02*
X610078Y424012D01*
G01D02*
X610127Y424132D01*
G01D02*
X610163Y424252D01*
G01D02*
X610195Y424385D01*
G01D02*
X610225Y424536D01*
G01D02*
X610254Y424708D01*
G01D02*
X610282Y424904D01*
G01D02*
X610311Y425126D01*
G01D02*
X610340Y425377D01*
G01D02*
X610369Y425660D01*
G01D02*
X610399Y425974D01*
G01D02*
X610430Y426323D01*
G01D02*
X610461Y426708D01*
G01D02*
X610493Y427132D01*
G01D02*
X610527Y427598D01*
G01D02*
X610538Y427756D01*
G01X615659Y423622D02*
X615745Y423629D01*
G01D02*
X616007Y423730D01*
G01D02*
X616166Y423882D01*
G01D02*
X616249Y424022D01*
G01D02*
X616298Y424144D01*
G01D02*
X616334Y424267D01*
G01D02*
X616365Y424401D01*
G01D02*
X616394Y424552D01*
G01D02*
X616423Y424726D01*
G01D02*
X616452Y424924D01*
G01D02*
X616480Y425149D01*
G01D02*
X616509Y425402D01*
G01D02*
X616538Y425683D01*
G01D02*
X616567Y425994D01*
G01D02*
X616597Y426333D01*
G01D02*
X616627Y426700D01*
G01D02*
X616657Y427098D01*
G01D02*
X616689Y427529D01*
G01D02*
X616705Y427756D01*
G01X612576Y423623D02*
X612662Y423629D01*
G01D02*
X612919Y423727D01*
G01D02*
X613076Y423873D01*
G01D02*
X613159Y424007D01*
G01D02*
X613207Y424124D01*
G01D02*
X613243Y424239D01*
G01D02*
X613274Y424363D01*
G01D02*
X613302Y424503D01*
G01D02*
X613319Y424596D01*
G01X606409Y423622D02*
X606498Y423629D01*
G01D02*
X606756Y423729D01*
G01D02*
X606911Y423876D01*
G01D02*
X606993Y424009D01*
G01D02*
X607041Y424124D01*
G01D02*
X607076Y424237D01*
G01D02*
X607107Y424361D01*
G01D02*
X607135Y424500D01*
G01D02*
X607163Y424658D01*
G01D02*
X607190Y424837D01*
G01D02*
X607217Y425041D01*
G01D02*
X607245Y425271D01*
G01D02*
X607273Y425529D01*
G01D02*
X607301Y425815D01*
G01D02*
X607330Y426129D01*
G01D02*
X607359Y426472D01*
G01D02*
X607389Y426844D01*
G01D02*
X607419Y427248D01*
G01D02*
X607455Y427756D01*
G01X620741Y424379D02*
X620749Y424409D01*
G01D02*
X620781Y424488D01*
G01D02*
X620868Y424613D01*
G01D02*
X621023Y424733D01*
G01D02*
X621235Y424800D01*
G01D02*
X621287Y424804D01*
G01X605416Y441661D02*
X605415Y441660D01*
G01D02*
X605398Y441621D01*
G01D02*
X605338Y441532D01*
G01D02*
X605198Y441416D01*
G01D02*
X604978Y441342D01*
G01D02*
X604911Y441338D01*
G01X621366Y423626D02*
X621581Y423694D01*
G01D02*
X621743Y423820D01*
G01D02*
X621838Y423963D01*
G01D02*
X621878Y424068D01*
G01D02*
X621890Y424114D01*
G01X636457Y612350D02*
X624646D01*
G01X636457D02*
X624646D01*
G01X620709Y616287D02*
Y793161D01*
G01Y616287D02*
Y793161D01*
G01Y616287D02*
G03X622708Y612860I3937J0D01*
G01X620709Y616287D02*
G03X622675Y612879I3937J0D01*
G01X622708Y612860D02*
G03X624646Y612350I1938J3427D01*
G01X622675Y612879D02*
G03X624646Y612350I1971J3409D01*
G01X638641Y827350D02*
X629574Y833394D01*
G01X638641Y827350D02*
X629574Y833394D01*
G01D02*
G03X627391Y834055I-2184J-3276D01*
G01X629574Y833394D02*
G03X627391Y834055I-2184J-3276D01*
G01X636457Y797098D02*
X624646D01*
G01X636457D02*
X624646D01*
G01X622708Y796589D02*
G03X620709Y793161I1938J-3427D01*
G01X622675Y796570D02*
G03X620709Y793161I1971J-3408D01*
G01X624646Y797098D02*
G03X622708Y796589I-2J-3937D01*
G01X624646Y797098D02*
G03X622675Y796570I-1J-3937D01*
G01X629574Y859520D02*
X638641Y865563D01*
G01X629574Y859520D02*
X638641Y865563D01*
G01X627391Y858858D02*
G03X629574Y859520I-2J3937D01*
G01X627391Y858858D02*
G03X629574Y859520I-2J3937D01*
G01X642693Y1003563D02*
X634032D01*
X635764Y1002264D01*
G01X642693D02*
Y1004862D01*
G01Y1012007D02*
X640817Y1012224D01*
X639229Y1012549D01*
X637785Y1012982D01*
X636197Y1013523D01*
X634032Y1014389D01*
Y1010059D01*
G01X640961Y1018503D02*
X641971Y1019153D01*
X642549Y1020019D01*
X642693Y1020993D01*
X642549Y1021859D01*
X641827Y1022726D01*
X640961Y1023267D01*
X640095Y1023375D01*
X639084Y1023159D01*
X638363Y1022401D01*
X638074Y1021643D01*
Y1020668D01*
G01Y1021643D02*
X637641Y1022292D01*
X636919Y1022834D01*
X636053Y1023050D01*
X635187Y1022834D01*
X634465Y1022292D01*
X634032Y1021318D01*
X634176Y1020344D01*
X634754Y1019369D01*
G01X642982Y1029546D02*
X642837Y1029329D01*
X642549D01*
X642404Y1029546D01*
X642549Y1029763D01*
X642837D01*
X642982Y1029546D01*
G01X639084Y1036150D02*
X638074Y1036908D01*
X637496Y1037557D01*
X637208Y1038424D01*
X637496Y1039181D01*
X638074Y1039723D01*
X638940Y1040156D01*
X639950Y1040264D01*
X640817Y1040156D01*
X641683Y1039723D01*
X642404Y1039073D01*
X642693Y1038315D01*
X642404Y1037449D01*
X641538Y1036691D01*
X640239Y1036258D01*
X638796Y1036150D01*
X636919Y1036366D01*
X635908Y1036691D01*
X634898Y1037233D01*
X634176Y1037990D01*
X634032Y1038748D01*
X634321Y1039506D01*
X635042Y1040048D01*
G01X639084Y1044811D02*
X638074Y1045569D01*
X637496Y1046218D01*
X637208Y1047085D01*
X637496Y1047842D01*
X638074Y1048384D01*
X638940Y1048817D01*
X639950Y1048925D01*
X640817Y1048817D01*
X641683Y1048384D01*
X642404Y1047734D01*
X642693Y1046976D01*
X642404Y1046110D01*
X641538Y1045352D01*
X640239Y1044919D01*
X638796Y1044811D01*
X636919Y1045027D01*
X635908Y1045352D01*
X634898Y1045894D01*
X634176Y1046651D01*
X634032Y1047409D01*
X634321Y1048167D01*
X635042Y1048709D01*
G01X649143Y-777373D02*
Y-796310D01*
G01X691528Y-599213D02*
Y-605512D01*
G01X640394Y112350D02*
Y3937D01*
G01Y112350D02*
Y3937D01*
G01X636457Y0D02*
G03X640394Y3937I0J3937D01*
G01X636457Y0D02*
G03X640394Y3937I0J3937D01*
G01X1284723Y0D02*
X652203D01*
G01X1284723D02*
X652203D01*
G01X648266Y3937D02*
Y83917D01*
G01Y3937D02*
Y83917D01*
G01Y3937D02*
G03X652203Y0I3937J0D01*
G01X648266Y3937D02*
G03X652203Y0I3937J0D01*
G01X648267Y34437D02*
G03X640393I-3937J0D01*
G01X640394Y128098D02*
Y3937D01*
G01Y128098D02*
Y3937D01*
G01Y128098D02*
Y3937D01*
G01X636457Y0D02*
G03X640394Y3937I0J3937D01*
G01X659085Y93237D02*
X650019Y87193D01*
G01X659085Y93237D02*
X650019Y87193D01*
G01X661269Y93898D02*
X742754D01*
G01X661269D02*
X742754D01*
G01X650019Y87193D02*
G03X648266Y83917I2185J-3276D01*
G01X661269Y93898D02*
G03X659085Y93237I0J-3937D01*
G01X661269Y93898D02*
G03X659085Y93237I0J-3937D01*
G01X650019Y87193D02*
G03X648266Y83917I2185J-3276D01*
G01X640393Y65146D02*
G03X648267I3937J0D01*
G01X635045Y71654D02*
X636063D01*
G01X635276Y76378D02*
X635866D01*
G01X636063Y77953D02*
X635045D01*
G01X635276Y76378D02*
Y75197D01*
G01X635866Y73228D02*
Y71654D01*
G01Y76378D02*
Y77953D01*
G01X636063Y71654D02*
Y77953D01*
G01X635045Y71654D02*
X636063D01*
G01X635276Y76378D02*
X635866D01*
G01X636063Y77953D02*
X635045D01*
G01X635276Y76378D02*
Y75197D01*
G01X635866Y73228D02*
Y71654D01*
G01Y76378D02*
Y77953D01*
G01X636063Y71654D02*
Y77953D01*
G01X661269Y118701D02*
X742754D01*
G01X661269D02*
X742754D01*
G01X650019Y125406D02*
X659085Y119362D01*
G01X650019Y125406D02*
X659085Y119362D01*
G01D02*
G03X661269Y118701I2184J3276D01*
G01X648266Y128682D02*
G03X650019Y125406I3937J0D01*
G01X648266Y128682D02*
G03X650019Y125406I3937J0D01*
G01X659085Y119362D02*
G03X661269Y118701I2184J3276D01*
G01X640394Y128098D02*
G03X636457Y132035I-3937J0D01*
G01X640394Y128098D02*
G03X636457Y132035I-3937J0D01*
G01X652203Y155657D02*
X664014D01*
G01X652203D02*
X664014D01*
G01X667951Y336469D02*
Y159594D01*
G01Y336469D02*
Y159594D01*
G01X648266Y128682D02*
Y151720D01*
G01Y128682D02*
Y151720D01*
G01X665952Y156167D02*
G03X667951Y159594I-1938J3427D01*
G01X665985Y156186D02*
G03X667951Y159594I-1971J3408D01*
G01X664014Y155657D02*
G03X665952Y156167I0J3937D01*
G01X652203Y155657D02*
G03X648266Y151720I0J-3937D01*
G01X652203Y155657D02*
G03X648266Y151720I0J-3937D01*
G01X664014Y155657D02*
G03X665985Y156186I0J3938D01*
G01X640394Y128098D02*
G03X636457Y132035I-3937J0D01*
G01X640394Y343759D02*
Y320720D01*
G01Y343759D02*
Y320720D01*
G01X636457Y316783D02*
G03X640394Y320720I0J3937D01*
G01X636457Y316783D02*
G03X640394Y320720I0J3937D01*
G01Y343759D02*
Y320720D01*
G01X636457Y316783D02*
G03X640394Y320720I0J3937D01*
G01Y468504D02*
Y388524D01*
G01Y468504D02*
Y388524D01*
G01Y343759D02*
G03X638641Y347035I-3938J0D01*
G01X640394Y343759D02*
G03X638641Y347035I-3938J0D01*
G01Y385248D02*
G03X640394Y388524I-2185J3276D01*
G01X638641Y385248D02*
G03X640394Y388524I-2185J3276D01*
G01X648266Y360091D02*
Y468504D01*
G01Y360091D02*
Y468504D01*
G01X652203Y340406D02*
X664014D01*
G01X652203D02*
X664014D01*
G01X648266Y344343D02*
Y468504D01*
G01Y344343D02*
Y468504D01*
G01X667951Y336469D02*
G03X665952Y339896I-3937J0D01*
G01X667951Y336469D02*
G03X665985Y339877I-3937J0D01*
G01X648266Y344343D02*
G03X652203Y340406I3937J0D01*
G01X665952Y339896D02*
G03X664014Y340406I-1938J-3427D01*
G01X648266Y344343D02*
G03X652203Y340406I3937J0D01*
G01X665985Y339877D02*
G03X664014Y340406I-1971J-3409D01*
G01X640394Y388524D02*
Y421048D01*
G01Y343759D02*
G03X638641Y347035I-3937J0D01*
G01Y385248D02*
G03X640394Y388524I-2184J3276D01*
G01X648267Y407295D02*
G03X640393I-3937J0D01*
G01Y438004D02*
G03X648267I3937J0D01*
G01X640394Y421048D02*
Y445094D01*
G01D02*
Y468504D01*
G01D02*
G03X636457Y472441I-3937J0D01*
G01X640394Y468504D02*
G03X636457Y472441I-3937J0D01*
G01X640394Y592665D02*
Y484252D01*
G01Y592665D02*
Y484252D01*
G01X636457Y480315D02*
G03X640394Y484252I0J3937D01*
G01X636457Y480315D02*
G03X640394Y484252I0J3937D01*
G01X1284723Y480315D02*
X652203D01*
G01X1284723D02*
X652203D01*
G01X648266Y484252D02*
Y564231D01*
G01Y484252D02*
Y564231D01*
G01Y484252D02*
G03X652203Y480315I3937J0D01*
G01X648266Y484252D02*
G03X652203Y480315I3937J0D01*
G01Y472441D02*
X1284723D01*
G01X652203D02*
X1284723D01*
G01X652203D02*
G03X648266Y468504I0J-3937D01*
G01X652203Y472441D02*
G03X648266Y468504I0J-3937D01*
G01X640394Y608413D02*
Y484252D01*
G01Y608413D02*
Y484252D01*
G01Y468504D02*
G03X636457Y472441I-3937J0D01*
G01X640393Y545462D02*
G03X648267I3937J0D01*
G01Y514753D02*
G03X640393I-3937J0D01*
G01X659085Y573552D02*
X650019Y567507D01*
G01X659085Y573552D02*
X650019Y567507D01*
G01X661269Y599016D02*
X742754D01*
G01X661269D02*
X742754D01*
G01X661269Y574213D02*
X742754D01*
G01X661269D02*
X742754D01*
G01X650019Y605721D02*
X659085Y599677D01*
G01X650019Y605721D02*
X659085Y599677D01*
G01D02*
G03X661269Y599016I2184J3276D01*
G01X648266Y608997D02*
G03X650019Y605721I3937J0D01*
G01X648266Y608997D02*
G03X650019Y605721I3937J0D01*
G01X659085Y599677D02*
G03X661269Y599016I2184J3276D01*
G01X650019Y567507D02*
G03X648266Y564231I2184J-3276D01*
G01X661269Y574213D02*
G03X659085Y573552I0J-3937D01*
G01X661269Y574213D02*
G03X659085Y573552I0J-3937D01*
G01X650019Y567507D02*
G03X648266Y564231I2184J-3276D01*
G01X640394Y608413D02*
G03X636457Y612350I-3937J0D01*
G01X640394Y608413D02*
G03X636457Y612350I-3937J0D01*
G01X648266Y608997D02*
Y632035D01*
G01Y608997D02*
Y632035D01*
G01X652203Y635972D02*
X664014D01*
G01X652203D02*
X664014D01*
G01X667951Y816783D02*
Y639909D01*
G01Y816783D02*
Y639909D01*
G01X665952Y636482D02*
G03X667951Y639909I-1938J3427D01*
G01X665985Y636501D02*
G03X667951Y639909I-1971J3408D01*
G01X664014Y635972D02*
G03X665952Y636482I0J3937D01*
G01X652203Y635972D02*
G03X648266Y632035I0J-3937D01*
G01X652203Y635972D02*
G03X648266Y632035I0J-3937D01*
G01X664014Y635972D02*
G03X665985Y636501I0J3938D01*
G01X640394Y824074D02*
G03X638641Y827350I-3938J0D01*
G01X640394Y824074D02*
G03X638641Y827350I-3938J0D01*
G01X648266Y840406D02*
Y948819D01*
G01Y840406D02*
Y948819D01*
G01X640394Y824074D02*
Y801035D01*
G01Y824074D02*
Y801035D01*
G01X636457Y797098D02*
G03X640394Y801035I0J3937D01*
G01X636457Y797098D02*
G03X640394Y801035I0J3937D01*
G01X652203Y820720D02*
X664014D01*
G01X652203D02*
X664014D01*
G01X648266Y824657D02*
Y948819D01*
G01Y824657D02*
Y948819D01*
G01X667951Y816783D02*
G03X665952Y820211I-3937J1D01*
G01X667951Y816783D02*
G03X665985Y820192I-3937J1D01*
G01X648266Y824657D02*
G03X652203Y820720I3937J0D01*
G01X665952Y820211D02*
G03X664014Y820720I-1936J-3428D01*
G01X648266Y824657D02*
G03X652203Y820720I3937J0D01*
G01X665985Y820192D02*
G03X664014Y820720I-1970J-3409D01*
G01X640394Y948819D02*
Y868839D01*
G01Y948819D02*
Y868839D01*
G01X638641Y865563D02*
G03X640394Y868839I-2185J3276D01*
G01X638641Y865563D02*
G03X640394Y868839I-2185J3276D01*
G01X648267Y887611D02*
G03X640393I-3937J0D01*
G01X640394Y948819D02*
G03X636457Y952756I-3937J0D01*
G01X640394Y948819D02*
G03X636457Y952756I-3937J0D01*
G01X652203D02*
X1284723D01*
G01X652203D02*
X1284723D01*
G01X652203D02*
G03X648266Y948819I0J-3937D01*
G01X652203Y952756D02*
G03X648266Y948819I0J-3937D01*
G01X640393Y918320D02*
G03X648267I3937J0D01*
G01Y952756D02*
Y1000315D01*
G01X640393Y952756D02*
Y1000315D01*
G01X652693Y1003563D02*
X644032D01*
X645764Y1002264D01*
G01X652693D02*
Y1004862D01*
G01Y1012007D02*
X650817Y1012224D01*
X649229Y1012549D01*
X647785Y1012982D01*
X646197Y1013523D01*
X644032Y1014389D01*
Y1010059D01*
G01X651394Y1018503D02*
X652116Y1019153D01*
X652549Y1019911D01*
X652693Y1020885D01*
X652404Y1021859D01*
X651827Y1022617D01*
X650817Y1023159D01*
X649662Y1023267D01*
X648507Y1023050D01*
X647785Y1022509D01*
X647208Y1021751D01*
X647063Y1020993D01*
X647208Y1020235D01*
X647785Y1019261D01*
X644032Y1019586D01*
Y1022509D01*
G01X652982Y1029546D02*
X652837Y1029329D01*
X652549D01*
X652404Y1029546D01*
X652549Y1029763D01*
X652837D01*
X652982Y1029546D01*
G01X649084Y1036150D02*
X648074Y1036908D01*
X647496Y1037557D01*
X647208Y1038424D01*
X647496Y1039181D01*
X648074Y1039723D01*
X648940Y1040156D01*
X649950Y1040264D01*
X650817Y1040156D01*
X651683Y1039723D01*
X652404Y1039073D01*
X652693Y1038315D01*
X652404Y1037449D01*
X651538Y1036691D01*
X650239Y1036258D01*
X648796Y1036150D01*
X646919Y1036366D01*
X645908Y1036691D01*
X644898Y1037233D01*
X644176Y1037990D01*
X644032Y1038748D01*
X644321Y1039506D01*
X645042Y1040048D01*
G01X649084Y1044811D02*
X648074Y1045569D01*
X647496Y1046218D01*
X647208Y1047085D01*
X647496Y1047842D01*
X648074Y1048384D01*
X648940Y1048817D01*
X649950Y1048925D01*
X650817Y1048817D01*
X651683Y1048384D01*
X652404Y1047734D01*
X652693Y1046976D01*
X652404Y1046110D01*
X651538Y1045352D01*
X650239Y1044919D01*
X648796Y1044811D01*
X646919Y1045027D01*
X645908Y1045352D01*
X644898Y1045894D01*
X644176Y1046651D01*
X644032Y1047409D01*
X644321Y1048167D01*
X645042Y1048709D01*
G01X649143Y1400383D02*
Y1381446D01*
G01X707276Y-599213D02*
Y-605512D01*
G01X711213Y-599213D02*
Y-605512D01*
G01X726961Y-599213D02*
Y-605512D01*
G01X742709D02*
Y-599213D01*
G01X746646Y-605512D02*
Y-599213D01*
G01X725552Y-7874D02*
G03Y0I0J3937D01*
G01X746691Y114764D02*
Y97835D01*
G01Y114764D02*
Y97835D01*
G01X742754Y93898D02*
G03X746691Y97835I0J3937D01*
G01X742754Y93898D02*
G03X746691Y97835I0J3937D01*
G01Y114764D02*
G03X742754Y118701I-3937J0D01*
G01X746691Y114764D02*
G03X742754Y118701I-3937J0D01*
G01X725552Y472441D02*
G03Y480315I0J3937D01*
G01X746691Y595079D02*
Y578150D01*
G01Y595079D02*
Y578150D01*
G01X742754Y574213D02*
G03X746691Y578150I0J3937D01*
G01Y595079D02*
G03X742754Y599016I-3937J0D01*
G01X746691Y595079D02*
G03X742754Y599016I-3937J0D01*
G01Y574213D02*
G03X746691Y578150I0J3937D01*
G01X725552Y952756D02*
G03Y960630I0J3937D01*
G01X756751Y-790183D02*
X757921Y-791483D01*
X759286Y-792263D01*
X761041Y-792523D01*
X762796Y-792003D01*
X764161Y-790963D01*
X765136Y-789143D01*
X765331Y-787063D01*
X764941Y-784983D01*
X763966Y-783683D01*
X762601Y-782643D01*
X761236Y-782383D01*
X759871Y-782643D01*
X758116Y-783683D01*
X758701Y-776923D01*
X763966D01*
G01X770150Y-612713D02*
X772750D01*
G01X780150D02*
X782750D01*
G01X790150D02*
X792750D01*
G01X800150D02*
X802750D01*
G01X760623Y-610630D02*
X758261D01*
G01Y-609055D02*
X760623D01*
G01X792385Y-599213D02*
X791549D01*
G01X758261D02*
X760623D01*
G01X765150D02*
X767709D01*
G01X797828D02*
X800387D01*
G01X793497Y-597638D02*
X793103D01*
G01X790741D02*
X790347D01*
G01X783654D02*
X783261D01*
G01X780898D02*
X780505D01*
G01X773812D02*
X773418D01*
G01X771056D02*
X770662D01*
G01X768950Y-595276D02*
X767709D01*
G01D02*
X765150D01*
G01D02*
X761213D01*
G01X768950D02*
X802946D01*
G01X768950Y-595213D02*
X809950D01*
G01X802750Y-594713D02*
X810750D01*
G01X758261Y-592126D02*
X765150D01*
G01D02*
X767709D01*
G01D02*
X768950D01*
G01D02*
X803536D01*
G01X800150Y-592113D02*
X810750D01*
G01X792414Y-591408D02*
X785032D01*
G01X783851D02*
X776469D01*
G01X797631Y-591339D02*
X795072D01*
G01X792709D02*
X776174D01*
G01X775002D02*
X772443D01*
G01X792414Y-590620D02*
X785032D01*
G01X783851D02*
X776469D01*
G01X768950Y-590613D02*
X809950D01*
G01X799402Y-590551D02*
X770465D01*
G01X791528Y-590464D02*
X786213D01*
G01X782670D02*
X777355D01*
G01X791528Y-590297D02*
X786213D01*
G01X782670D02*
X777355D01*
G01X778143Y-590156D02*
X782670D01*
G01X787985D02*
X791528D01*
G01X787985Y-590116D02*
X786213D01*
G01X778143D02*
X777355D01*
G01X791528Y-589949D02*
X786213D01*
G01X782670D02*
X777355D01*
G01X791528Y-589919D02*
X787985D01*
G01X782670D02*
X778143D01*
G01X792020Y-589883D02*
X791824D01*
G01X785918D02*
X785721D01*
G01X783162D02*
X782965D01*
G01X777060D02*
X776863D01*
G01X792020Y-589699D02*
X791980D01*
G01X791824D02*
X791748D01*
G01X785763D02*
X785721D01*
G01X787985D02*
X786017D01*
G01X785993D02*
X785918D01*
G01X783162D02*
X783121D01*
G01X782965D02*
X782890D01*
G01X778143D02*
X776863D01*
G01X792020Y-589435D02*
X791980D01*
G01X791824D02*
X791748D01*
G01X785993D02*
X785918D01*
G01X787985D02*
X786017D01*
G01X785763D02*
X785721D01*
G01X782965D02*
X782890D01*
G01X783162D02*
X783121D01*
G01X778143D02*
X776863D01*
G01X792020Y-589251D02*
X791824D01*
G01X785918D02*
X785721D01*
G01X783162D02*
X782965D01*
G01X777060D02*
X776863D01*
G01X791528Y-589215D02*
X787985D01*
G01X782670D02*
X778143D01*
G01X791528Y-589185D02*
X786213D01*
G01X782670D02*
X777355D01*
G01X787985Y-589018D02*
X786213D01*
G01X778143D02*
X777355D01*
G01X778143Y-588978D02*
X782670D01*
G01X787985D02*
X791528D01*
G01Y-588837D02*
X786213D01*
G01X782670D02*
X777355D01*
G01X791528Y-588670D02*
X786213D01*
G01X782670D02*
X777355D01*
G01X776174Y-588583D02*
X792709D01*
G01X792414Y-588432D02*
X785032D01*
G01X783851D02*
X776469D01*
G01X792414Y-587180D02*
X785032D01*
G01X783851D02*
X776469D01*
G01X792414Y-587030D02*
X785032D01*
G01X783851D02*
X776469D01*
G01X776174Y-587008D02*
X792709D01*
G01X792414Y-586817D02*
X784975D01*
G01X783909D02*
X776469D01*
G01X792414Y-586754D02*
X784975D01*
G01X783909D02*
X776469D01*
G01X799402Y-585827D02*
X829127D01*
G01X795859Y-585433D02*
X787985D01*
G01X786017D02*
X778143D01*
G01X776174D02*
X768300D01*
G01X803536Y-585039D02*
X799370D01*
G01X792414Y-584977D02*
X776469D01*
G01X792414Y-584915D02*
X776469D01*
G01X792414Y-584843D02*
X776469D01*
G01X792750Y-584713D02*
X810750D01*
G01X776174Y-584646D02*
X792709D01*
G01X821450Y-582677D02*
X805702D01*
G01X808457D02*
X770465D01*
G01X758261Y-570472D02*
Y-599213D01*
G01D02*
Y-605512D01*
G01Y-610630D02*
Y-605512D01*
G01X760623Y-610630D02*
Y-605512D01*
G01D02*
Y-599213D01*
G01D02*
Y-566929D01*
G01X761213Y-595276D02*
Y-592126D01*
G01X765150D02*
Y-599213D01*
G01X767631Y-592126D02*
Y-595276D01*
G01X767709Y-599213D02*
Y-592126D01*
G01X768001Y-595276D02*
Y-592126D01*
G01X768300Y-591732D02*
Y-585433D01*
G01X768672Y-595276D02*
Y-592126D01*
G01X768950Y-599213D02*
Y-549713D01*
G01X769042Y-592126D02*
Y-595276D01*
G01X769875Y-596850D02*
Y-595276D01*
G01X770150Y-562113D02*
Y-605512D01*
G01D02*
Y-612713D01*
G01X770200Y-605512D02*
Y-612713D01*
G01Y-605512D02*
Y-557613D01*
G01X770465Y-590551D02*
Y-575197D01*
G01X771056Y-611024D02*
Y-597638D01*
G01X771843Y-575197D02*
Y-590551D01*
G01X772434Y-575197D02*
Y-590551D01*
G01X772443D02*
Y-591339D01*
G01X772700Y-612713D02*
Y-605512D01*
G01D02*
Y-557613D01*
G01X772750Y-612713D02*
Y-605512D01*
G01D02*
Y-564713D01*
G01X773418Y-597638D02*
Y-605512D01*
G01D02*
Y-611024D01*
G01X774150Y-577213D02*
Y-599213D01*
G01X774402Y-575197D02*
Y-590551D01*
G01X774599Y-595276D02*
Y-596850D01*
G01X774993Y-575197D02*
Y-590551D01*
G01X775002D02*
Y-591339D01*
G01X775550Y-592126D02*
Y-595276D01*
G01X775920Y-592126D02*
Y-595276D01*
G01X776174Y-584646D02*
Y-591732D01*
G01X776371Y-582677D02*
Y-590551D01*
G01X776469Y-591408D02*
Y-584646D01*
G01X776592Y-592126D02*
Y-595276D01*
G01X776765Y-592126D02*
Y-597441D01*
G01X776863Y-589251D02*
Y-589883D01*
G01X776962Y-592126D02*
Y-595276D01*
G01X777060Y-589251D02*
Y-589883D01*
G01X777355Y-588670D02*
Y-590464D01*
G01X778143Y-591732D02*
Y-585433D01*
G01X779717Y-596850D02*
Y-595276D01*
G01X780150Y-572113D02*
Y-605512D01*
G01D02*
Y-612713D01*
G01X780200Y-605512D02*
Y-612713D01*
G01Y-605512D02*
Y-557613D01*
G01X780308Y-597441D02*
Y-592126D01*
G01X780898Y-611024D02*
Y-597638D01*
G01X782670Y-588670D02*
Y-589215D01*
G01Y-589919D02*
Y-590464D01*
G01X782700Y-612713D02*
Y-605512D01*
G01D02*
Y-557613D01*
G01X782750Y-612713D02*
Y-605512D01*
G01D02*
Y-574713D01*
G01X782890Y-589435D02*
Y-589699D01*
G01X782965Y-589251D02*
Y-589883D01*
G01X783121Y-589435D02*
Y-589699D01*
G01X783162Y-589251D02*
Y-589883D01*
G01X783261Y-597638D02*
Y-605512D01*
G01D02*
Y-611024D01*
G01X783851Y-587030D02*
Y-591408D01*
G01X783909Y-586754D02*
Y-586817D01*
G01X784442Y-592126D02*
Y-597441D01*
G01X784975Y-586754D02*
Y-586817D01*
G01X785032Y-591408D02*
Y-587030D01*
G01X785721Y-589251D02*
Y-589883D01*
G01X785763Y-589435D02*
Y-589699D01*
G01X785918Y-589251D02*
Y-589883D01*
G01X785993Y-589435D02*
Y-589699D01*
G01X786017Y-585433D02*
Y-591732D01*
G01X786213Y-588670D02*
Y-590464D01*
G01X787828Y-592126D02*
Y-595276D01*
G01X787985Y-597441D02*
Y-592126D01*
G01Y-591732D02*
Y-585433D01*
G01X788198Y-592126D02*
Y-595276D01*
G01X788869Y-592126D02*
Y-595276D01*
G01X789239Y-592126D02*
Y-595276D01*
G01X789560Y-596850D02*
Y-595276D01*
G01X790150Y-582113D02*
Y-605512D01*
G01D02*
Y-612713D01*
G01X790200Y-605512D02*
Y-612713D01*
G01Y-605512D02*
Y-557613D01*
G01X790741Y-611024D02*
Y-597638D01*
G01X791528Y-588670D02*
Y-589215D01*
G01Y-589919D02*
Y-590464D01*
G01X791748Y-589435D02*
Y-589699D01*
G01X791824Y-589251D02*
Y-589883D01*
G01X791980Y-589435D02*
Y-589699D01*
G01X792020Y-589251D02*
Y-589883D01*
G01X792414Y-591408D02*
Y-584646D01*
G01X792513Y-582677D02*
Y-590551D01*
G01X792700Y-612713D02*
Y-605512D01*
G01D02*
Y-557613D01*
G01X792709Y-584646D02*
Y-591339D01*
G01X792750Y-612713D02*
Y-605512D01*
G01D02*
Y-584713D01*
G01X793103Y-597638D02*
Y-605512D01*
G01D02*
Y-611024D01*
G01X793556Y-605512D02*
Y-599213D01*
G01X793950Y-577213D02*
Y-599213D01*
G01X794284Y-595276D02*
Y-596850D01*
G01Y-590551D02*
Y-575197D01*
G01X794875D02*
Y-590551D01*
G01X795072D02*
Y-591339D01*
G01X783909Y-586754D02*
X783893Y-586879D01*
G01X783909Y-586817D02*
X783893Y-586879D01*
G01X784975Y-586817D02*
X784991Y-586879D01*
G01X784975Y-586754D02*
X784991Y-586879D01*
G01X803143Y-585897D02*
X803157Y-586406D01*
G01X804336Y-586339D02*
X804324Y-585886D01*
G01X805511Y-586099D02*
X805494Y-585493D01*
G01X804307Y-585244D02*
X804324Y-585897D01*
G01X804287Y-584404D02*
X804307Y-585244D01*
G01X805494Y-585493D02*
X805475Y-584713D01*
G01X804267Y-583535D02*
X804287Y-584404D01*
G01X804247Y-582648D02*
X804267Y-583535D01*
G01X804163Y-578713D02*
X804247Y-582648D01*
G01X795859Y-585433D02*
Y-591732D01*
G01X796495Y-592126D02*
Y-595276D01*
G01X796843Y-575197D02*
Y-590551D01*
G01X796865Y-592126D02*
Y-595276D01*
G01X797434Y-575197D02*
Y-590551D01*
G01X797537Y-592126D02*
Y-595276D01*
G01X797631Y-590551D02*
Y-591339D01*
G01X797828Y-592126D02*
Y-599213D01*
G01X797907Y-592126D02*
Y-595276D01*
G01X799370Y-576378D02*
Y-585039D01*
G01X799402Y-569685D02*
Y-590551D01*
G01X800150Y-592113D02*
Y-605512D01*
G01D02*
Y-612713D01*
G01X800200Y-605512D02*
Y-612713D01*
G01Y-605512D02*
Y-557613D01*
G01X800387Y-576378D02*
Y-585039D01*
G01Y-609055D02*
Y-592126D01*
G01X802700Y-612713D02*
Y-605512D01*
G01D02*
Y-557613D01*
G01X802750Y-612713D02*
Y-605512D01*
G01D02*
Y-594713D01*
G01X802946Y-592126D02*
Y-595276D01*
G01X803536Y-605512D02*
Y-609055D01*
G01Y-605512D02*
Y-566929D01*
G01X804350Y-595213D02*
Y-599213D01*
G01X805702Y-582677D02*
Y-599213D01*
G01X803572Y-582323D02*
X803551Y-583265D01*
G01X804731Y-583329D02*
X804829Y-578781D01*
G01X803551Y-583265D02*
X803531Y-584142D01*
G01X804712Y-584158D02*
X804731Y-583329D01*
G01X805024Y-581331D02*
X804931Y-583412D01*
G01D02*
X804888Y-584353D01*
G01X806053Y-584713D02*
X806079Y-584149D01*
G01X800387Y-609055D02*
G03X802758Y-610414I1575J0D01*
G01D02*
G03X803536Y-609055I-797J1358D01*
G01X771056Y-611024D02*
G03X772756Y-612085I1181J0D01*
G01X780898Y-611024D02*
G03X782752Y-611995I1181J0D01*
G01X790741Y-611024D02*
G03X792760Y-611856I1181J0D01*
G01X772756Y-612085D02*
G03X773418Y-611024I-519J1061D01*
G01X782752Y-611995D02*
G03X783261Y-611024I-672J971D01*
G01X792760Y-611856D02*
G03X793103Y-611024I-838J832D01*
G01X784442Y-597441D02*
G03X787985I1771J0D01*
G01X776765D02*
G03X780308I1771J0D01*
G01X773812Y-597638D02*
G03X774599Y-596850I0J787D01*
G01X769875D02*
G03X770662Y-597638I787J-1D01*
G01X783654D02*
G03X784442Y-596850I1J787D01*
G01X779717D02*
G03X780505Y-597638I788J0D01*
G01X793497D02*
G03X794284Y-596850I0J787D01*
G01X789560D02*
G03X790347Y-597638I787J-1D01*
G01X772443Y-591339D02*
G03X773230Y-592126I787J0D01*
G01X774214D02*
G03X775002Y-591339I1J787D01*
G01X768300Y-591732D02*
G03X768406Y-592126I787J1D01*
G01X776069D02*
G03X776174Y-591732I-682J393D01*
G01X778143D02*
G03X778248Y-592126I787J-1D01*
G01X783121Y-589435D02*
G03X782993Y-589120I-451J0D01*
G01Y-590014D02*
G03X783121Y-589699I-323J315D01*
G01X782752Y-588679D02*
G03X782700Y-588672I-82J-415D01*
G01Y-590462D02*
G03X782752Y-590456I-22J423D01*
G01X782700Y-588672D02*
G03X782670Y-588670I-42J-404D01*
G01Y-590464D02*
G03X782700Y-590463I1J407D01*
G01X782751Y-589195D02*
G03X782700Y-589187I-79J-337D01*
G01Y-589948D02*
G03X782751Y-589939I-35J345D01*
G01X782700Y-589186D02*
G03X782670Y-589185I-26J-344D01*
G01Y-589949D02*
G03X782700Y-589948I4J344D01*
G01X782890Y-589435D02*
G03X782670Y-589215I-220J0D01*
G01Y-589919D02*
G03X782890Y-589699I0J220D01*
G01X782670Y-590296D02*
G03X782700Y-590294I1J210D01*
G01Y-588840D02*
G03X782670Y-588838I-29J-208D01*
G01X795072Y-591339D02*
G03X795859Y-592126I787J0D01*
G01X796843D02*
G03X797631Y-591339I1J787D01*
G01X785911Y-592126D02*
G03X786017Y-591732I-681J395D01*
G01X795754Y-592126D02*
G03X795859Y-591732I-682J393D01*
G01X787985D02*
G03X788091Y-592126I787J1D01*
G01X785762Y-589699D02*
G03X785891Y-590014I451J1D01*
G01Y-589120D02*
G03X785762Y-589435I322J-316D01*
G01X791980D02*
G03X791852Y-589120I-452J0D01*
G01Y-590014D02*
G03X791980Y-589699I-323J315D01*
G01X786017Y-589337D02*
G03X785993Y-589435I196J-100D01*
G01Y-589699D02*
G03X786017Y-589797I220J2D01*
G01X791748Y-589435D02*
G03X791528Y-589215I-220J0D01*
G01Y-589919D02*
G03X791748Y-589699I0J220D01*
G01X804100Y-584733D02*
G03X804165Y-582115I-738368J19642D01*
G01X802697Y-588133D02*
G03X803536Y-588189I828J6091D01*
G01X802697Y-588132D02*
G03X803536Y-588189I835J6086D01*
G01X804824Y-582120D02*
G03X804878Y-584718I1170953J23039D01*
G01Y-584717D02*
G03X804914Y-586250I521128J11471D01*
G01X804465Y-589206D02*
X804464Y-589204D01*
G01D02*
X804461Y-589184D01*
G01D02*
X804457Y-589149D01*
G01D02*
X804452Y-589100D01*
G01D02*
X804446Y-589039D01*
G01D02*
X804441Y-588965D01*
G01D02*
X804435Y-588880D01*
G01D02*
X804428Y-588783D01*
G01D02*
X804422Y-588673D01*
G01D02*
X804415Y-588552D01*
G01D02*
X804409Y-588417D01*
G01D02*
X804402Y-588271D01*
G01D02*
X804395Y-588111D01*
G01D02*
X804388Y-587939D01*
G01D02*
X804381Y-587752D01*
G01D02*
X804374Y-587552D01*
G01D02*
X804367Y-587338D01*
G01D02*
X804359Y-587109D01*
G01D02*
X804352Y-586867D01*
G01D02*
X804344Y-586610D01*
G01D02*
X804330Y-586133D01*
G01X804587Y-589150D02*
X804585Y-589158D01*
G01D02*
X804592Y-589138D01*
G01D02*
X804621Y-589073D01*
G01D02*
X804698Y-588965D01*
G01D02*
X804844Y-588852D01*
G01D02*
X805051Y-588784D01*
G01D02*
X805123Y-588780D01*
G01X803349Y-589190D02*
X803347Y-589205D01*
G01D02*
X803348Y-589202D01*
G01D02*
X803357Y-589168D01*
G01D02*
X803390Y-589090D01*
G01D02*
X803472Y-588972D01*
G01D02*
X803626Y-588851D01*
G01D02*
X803842Y-588783D01*
G01D02*
X803906Y-588779D01*
G01X804888Y-584353D02*
X804868Y-584794D01*
G01D02*
X804848Y-585215D01*
G01D02*
X804829Y-585614D01*
G01D02*
X804810Y-585991D01*
G01D02*
X804793Y-586346D01*
G01D02*
X804775Y-586677D01*
G01D02*
X804758Y-586986D01*
G01D02*
X804742Y-587272D01*
G01D02*
X804726Y-587537D01*
G01D02*
X804711Y-587779D01*
G01D02*
X804697Y-588000D01*
G01D02*
X804683Y-588201D01*
G01D02*
X804669Y-588381D01*
G01D02*
X804656Y-588543D01*
G01D02*
X804644Y-588684D01*
G01D02*
X804632Y-588806D01*
G01D02*
X804621Y-588910D01*
G01D02*
X804611Y-588996D01*
G01D02*
X804602Y-589065D01*
G01D02*
X804594Y-589115D01*
G01D02*
X804587Y-589148D01*
G01D02*
Y-589150D01*
G01X806079Y-584149D02*
X806102Y-583642D01*
G01D02*
X806150Y-582568D01*
G01D02*
X806201Y-581424D01*
G01X803531Y-584142D02*
X803512Y-584943D01*
G01D02*
X803503Y-585315D01*
G01D02*
X803494Y-585669D01*
G01D02*
X803485Y-586003D01*
G01D02*
X803476Y-586320D01*
G01D02*
X803467Y-586619D01*
G01D02*
X803459Y-586900D01*
G01D02*
X803451Y-587165D01*
G01D02*
X803443Y-587412D01*
G01D02*
X803434Y-587641D01*
G01D02*
X803426Y-587854D01*
G01D02*
X803419Y-588049D01*
G01D02*
X803411Y-588228D01*
G01D02*
X803404Y-588390D01*
G01D02*
X803397Y-588537D01*
G01D02*
X803390Y-588668D01*
G01D02*
X803383Y-588784D01*
G01D02*
X803376Y-588886D01*
G01D02*
X803370Y-588973D01*
G01D02*
X803364Y-589047D01*
G01D02*
X803359Y-589108D01*
G01D02*
X803354Y-589155D01*
G01D02*
X803350Y-589188D01*
G01D02*
X803349Y-589190D01*
G01X805440Y-583181D02*
X805413Y-581983D01*
G01X805475Y-584713D02*
X805467Y-584362D01*
G01D02*
X805453Y-583776D01*
G01D02*
X805440Y-583181D01*
G01X803157Y-586406D02*
X803165Y-586701D01*
G01D02*
X803174Y-586979D01*
G01D02*
X803182Y-587240D01*
G01D02*
X803190Y-587485D01*
G01D02*
X803198Y-587712D01*
G01D02*
X803206Y-587924D01*
G01D02*
X803214Y-588119D01*
G01D02*
X803221Y-588299D01*
G01D02*
X803229Y-588464D01*
G01D02*
X803237Y-588615D01*
G01D02*
X803244Y-588752D01*
G01D02*
X803251Y-588875D01*
G01D02*
X803258Y-588986D01*
G01D02*
X803266Y-589084D01*
G01D02*
X803273Y-589172D01*
G01D02*
X803280Y-589249D01*
G01D02*
X803289Y-589319D01*
G01D02*
X803297Y-589381D01*
G01D02*
X803309Y-589443D01*
G01D02*
X803327Y-589514D01*
G01D02*
X803367Y-589619D01*
G01D02*
X803460Y-589759D01*
G01D02*
X803617Y-589885D01*
G01D02*
X803826Y-589955D01*
G01D02*
X803906Y-589960D01*
G01X804340Y-586483D02*
X804350Y-586813D01*
G01D02*
X804361Y-587121D01*
G01D02*
X804371Y-587408D01*
G01D02*
X804381Y-587675D01*
G01D02*
X804392Y-587920D01*
G01D02*
X804402Y-588145D01*
G01D02*
X804413Y-588350D01*
G01D02*
X804423Y-588534D01*
G01D02*
X804434Y-588700D01*
G01D02*
X804444Y-588847D01*
G01D02*
X804455Y-588978D01*
G01D02*
X804466Y-589092D01*
G01D02*
X804477Y-589193D01*
G01D02*
X804488Y-589281D01*
G01D02*
X804501Y-589361D01*
G01D02*
X804517Y-589436D01*
G01D02*
X804539Y-589518D01*
G01D02*
X804581Y-589620D01*
G01D02*
X804669Y-589752D01*
G01D02*
X804824Y-589880D01*
G01D02*
X805041Y-589955D01*
G01D02*
X805123Y-589960D01*
G01X805666Y-589169D02*
Y-589170D01*
G01D02*
X805663Y-589157D01*
G01D02*
X805657Y-589120D01*
G01D02*
X805650Y-589064D01*
G01D02*
X805642Y-588989D01*
G01D02*
X805633Y-588898D01*
G01D02*
X805624Y-588791D01*
G01D02*
X805615Y-588666D01*
G01D02*
X805606Y-588524D01*
G01D02*
X805596Y-588365D01*
G01D02*
X805587Y-588188D01*
G01D02*
X805577Y-587993D01*
G01D02*
X805567Y-587779D01*
G01D02*
X805558Y-587547D01*
G01D02*
X805548Y-587295D01*
G01D02*
X805539Y-587025D01*
G01D02*
X805530Y-586735D01*
G01D02*
X805520Y-586427D01*
G01D02*
X805511Y-586099D01*
G01X805123Y-588780D02*
X805208Y-588786D01*
G01D02*
X805412Y-588857D01*
G01D02*
X805555Y-588972D01*
G01D02*
X805632Y-589085D01*
G01D02*
X805660Y-589152D01*
G01D02*
X805666Y-589169D01*
G01X803906Y-588779D02*
X803986Y-588785D01*
G01D02*
X804193Y-588855D01*
G01D02*
X804342Y-588974D01*
G01D02*
X804426Y-589098D01*
G01D02*
X804456Y-589174D01*
G01D02*
X804464Y-589204D01*
G01D02*
X804465Y-589206D01*
G01X803906Y-589960D02*
X803974Y-589956D01*
G01D02*
X804189Y-589888D01*
G01D02*
X804351Y-589760D01*
G01D02*
X804446Y-589617D01*
G01D02*
X804485Y-589512D01*
G01D02*
X804504Y-589440D01*
G01D02*
X804515Y-589378D01*
G01D02*
X804524Y-589313D01*
G01D02*
X804532Y-589242D01*
G01D02*
X804539Y-589161D01*
G01D02*
X804547Y-589069D01*
G01D02*
X804555Y-588964D01*
G01D02*
X804562Y-588846D01*
G01D02*
X804570Y-588714D01*
G01D02*
X804578Y-588567D01*
G01D02*
X804585Y-588406D01*
G01D02*
X804593Y-588231D01*
G01D02*
X804601Y-588041D01*
G01D02*
X804609Y-587836D01*
G01D02*
X804617Y-587616D01*
G01D02*
X804625Y-587380D01*
G01D02*
X804633Y-587129D01*
G01D02*
X804641Y-586862D01*
G01D02*
X804650Y-586580D01*
G01D02*
X804658Y-586281D01*
G01D02*
X804667Y-585967D01*
G01D02*
X804676Y-585637D01*
G01D02*
X804685Y-585291D01*
G01D02*
X804712Y-584158D01*
G01X805123Y-589960D02*
X805193Y-589956D01*
G01D02*
X805413Y-589885D01*
G01D02*
X805572Y-589759D01*
G01D02*
X805661Y-589630D01*
G01D02*
X805704Y-589530D01*
G01D02*
X805728Y-589449D01*
G01D02*
X805745Y-589374D01*
G01D02*
X805760Y-589296D01*
G01D02*
X805773Y-589207D01*
G01D02*
X805786Y-589106D01*
G01D02*
X805800Y-588989D01*
G01D02*
X805813Y-588855D01*
G01D02*
X805827Y-588701D01*
G01D02*
X805842Y-588527D01*
G01D02*
X805857Y-588332D01*
G01D02*
X805872Y-588117D01*
G01D02*
X805887Y-587879D01*
G01D02*
X805904Y-587619D01*
G01D02*
X805920Y-587335D01*
G01D02*
X805938Y-587026D01*
G01D02*
X805956Y-586693D01*
G01D02*
X805975Y-586332D01*
G01D02*
X805994Y-585946D01*
G01D02*
X806014Y-585533D01*
G01D02*
X806035Y-585096D01*
G01D02*
X806053Y-584713D01*
G01X790150Y-582113D02*
X810750D01*
G01X770465Y-578346D02*
X790544D01*
G01X791725D02*
X811410D01*
G01X861950Y-577213D02*
X768950D01*
G01X803536Y-576378D02*
X799370D01*
G01X770465Y-575197D02*
X783563D01*
G01X783654D02*
X829127D01*
G01X782750Y-574713D02*
X810750D01*
G01X803930Y-573819D02*
X762985D01*
G01X780150Y-572113D02*
X810750D01*
G01X798221Y-571063D02*
X785623D01*
G01X758261Y-570472D02*
X760623D01*
G01X768103Y-569882D02*
X790150D01*
G01X771282Y-569694D02*
X769369D01*
G01X785623Y-569685D02*
X779324D01*
G01X760623D02*
X771198D01*
G01X790150D02*
X806095D01*
G01X771362Y-569309D02*
X769449D01*
G01X758064Y-569291D02*
X768950D01*
G01D02*
X806095D01*
G01X768950Y-566929D02*
X758064D01*
G01X768950D02*
X806095D01*
G01X772750Y-564713D02*
X810750D01*
G01X770150Y-562113D02*
X810750D01*
G01X829450Y-557613D02*
X768950D01*
G01X810750Y-553713D02*
X789450D01*
G01X768950Y-549713D02*
X861950D01*
G01X786597Y-573285D02*
X769369Y-569694D01*
G01X787372Y-573399D02*
X786547Y-573227D01*
G01X786578Y-572930D02*
X787403Y-573103D01*
G01X771282Y-569694D02*
X786637Y-572895D01*
G01X769449Y-569309D02*
X786677Y-572900D01*
G01X787451Y-573030D02*
X786807Y-572896D01*
G01X787485Y-572702D02*
X786841Y-572568D01*
G01X786718Y-572510D02*
X771362Y-569309D01*
G01X758064Y-569291D02*
Y-566929D01*
G01X761410Y-569291D02*
Y-569685D01*
G01X762198Y-569291D02*
Y-569685D01*
G01X762985Y-573819D02*
Y-569291D01*
G01X764560D02*
Y-569685D01*
G01X766922D02*
Y-569291D01*
G01X768103D02*
Y-569882D01*
G01X768891Y-569291D02*
Y-569685D01*
G01X769284Y-569291D02*
Y-569685D01*
G01X771198D02*
Y-569291D01*
G01X769369Y-569694D02*
X769449Y-569309D01*
G01X771282Y-569694D02*
X771362Y-569309D01*
G01X779324Y-569685D02*
X777355Y-575197D01*
G01X778339D02*
Y-578346D01*
G01X779127D02*
Y-575197D01*
G01X781489D02*
Y-578346D01*
G01X781883Y-566929D02*
Y-569291D01*
G01X783563Y-575197D02*
Y-578346D01*
G01X783654D02*
Y-575197D01*
G01X785623Y-569685D02*
Y-571063D01*
G01X785820Y-569291D02*
Y-566929D01*
G01X786017Y-575197D02*
Y-578346D01*
G01X786472Y-575197D02*
Y-578346D01*
G01X788182Y-566929D02*
Y-569291D01*
G01X789450Y-557613D02*
Y-549713D01*
G01X790150Y-569882D02*
Y-569291D01*
G01X790544Y-575197D02*
Y-578346D01*
G01X791725D02*
Y-575197D01*
G01X793694Y-569291D02*
Y-569685D01*
G01X794087Y-569291D02*
Y-569685D01*
G01X794435Y-569291D02*
Y-569685D01*
G01X794481Y-569291D02*
Y-569685D01*
G01X794678Y-575197D02*
Y-571063D01*
G01X786547Y-573227D02*
X786578Y-572930D01*
G01X786841Y-572568D02*
X786807Y-572896D01*
G01X787176Y-572814D02*
X787146Y-573111D01*
G01X787372Y-573399D02*
X787371Y-573415D01*
G01X787405Y-573087D02*
X787403Y-573103D01*
G01X787445Y-573053D02*
X787476Y-572756D01*
G01X787524Y-572683D02*
X787557Y-572356D01*
G01X786637Y-572895D02*
X786718Y-572510D01*
G01X786677Y-572900D02*
X786597Y-573285D01*
G01X787557Y-572356D02*
X787405Y-573087D01*
G01X787476Y-572756D02*
X787403Y-573103D01*
G01X787445Y-573053D02*
X787372Y-573399D01*
G01X787524Y-572683D02*
X787371Y-573415D01*
G01X804054Y-574269D02*
X804067Y-574713D01*
G01X805248D02*
X805237Y-574340D01*
G01X804067Y-574713D02*
X804078Y-575108D01*
G01D02*
X804094Y-575733D01*
G01D02*
X804111Y-576410D01*
G01D02*
X804129Y-577213D01*
G01D02*
X804145Y-577905D01*
G01X805329Y-578033D02*
X805296Y-576599D01*
G01X804145Y-577905D02*
X804163Y-578713D01*
G01X805352Y-579091D02*
X805329Y-578033D01*
G01X805401Y-581386D02*
X805352Y-579091D01*
G01X797788Y-569291D02*
Y-569685D01*
G01X798221D02*
Y-575197D01*
G01X798404Y-566929D02*
Y-569291D01*
G01X799993D02*
Y-566929D01*
G01X800229Y-569291D02*
Y-569685D01*
G01X801765D02*
Y-575197D01*
G01X803733Y-569685D02*
Y-569291D01*
G01X803930D02*
Y-573819D01*
G01X804520Y-569291D02*
Y-569685D01*
G01X804717Y-569291D02*
Y-569685D01*
G01X805308Y-569291D02*
Y-569685D01*
G01X806095Y-571063D02*
Y-566929D01*
G01X803657Y-578328D02*
X803572Y-582323D01*
G01X804829Y-578781D02*
X804848Y-577913D01*
G01D02*
X804866Y-577094D01*
G01D02*
X804884Y-576331D01*
G01X804725Y-577212D02*
G03X804667Y-574683I-693950J-14650D01*
G01X803536Y-573228D02*
G03X802699Y-573285I-2J-6150D01*
G01X803536Y-573228D02*
G03X802697Y-573285I-4J-6147D01*
G01X800191Y-574439D02*
G03X799965Y-574696I2225J-2185D01*
G01X800190Y-574441D02*
G03X799961Y-574702I2195J-2157D01*
G01X769449Y-569309D02*
G03X769284Y-569291I-169J-782D01*
G01X771362Y-569309D02*
G03X771198Y-569291I-169J-782D01*
G01X787524Y-572683D02*
G03X786807Y-572896I-161J-771D01*
G01X787557Y-572356D02*
G03X786841Y-572568I-161J-771D01*
G01X786578Y-572931D02*
G03X787176Y-572814I160J771D01*
G01X786547Y-573227D02*
G03X787146Y-573111I161J771D01*
G01X769369Y-569694D02*
G03X769284Y-569685I-86J-410D01*
G01X771282Y-569694D02*
G03X771198Y-569685I-86J-410D01*
G01X787476Y-572756D02*
G03X787176Y-572814I-81J-386D01*
G01X787445Y-573053D02*
G03X787146Y-573111I-80J-385D01*
G01X802134Y-569291D02*
G03X806095Y-571063I3962J3543D01*
G01X760615Y-569412D02*
G03X766272Y-569291I2764J3073D01*
G01X760486D02*
G03X760615Y-569412I2892J2954D01*
G01X803389Y-566929D02*
G03X806095Y-568701I2706J1181D01*
G01X761709Y-566929D02*
G03X765049I1670J591D01*
G01X804348Y-574683D02*
G03X804279Y-577204I399309J-12191D01*
G01X802699Y-573285D02*
X802697D01*
G01X805938Y-572109D02*
X805957Y-572215D01*
G01D02*
X805978Y-572343D01*
G01D02*
X806000Y-572493D01*
G01D02*
X806022Y-572667D01*
G01D02*
X806045Y-572862D01*
G01D02*
X806069Y-573080D01*
G01D02*
X806093Y-573322D01*
G01D02*
X806118Y-573586D01*
G01D02*
X806143Y-573874D01*
G01D02*
X806168Y-574185D01*
G01D02*
X806194Y-574520D01*
G01X803938Y-571822D02*
Y-571820D01*
G01D02*
X803941Y-571842D01*
G01D02*
X803945Y-571879D01*
G01D02*
X803951Y-571930D01*
G01D02*
X803956Y-571994D01*
G01D02*
X803962Y-572070D01*
G01X805633Y-572056D02*
X805606Y-572225D01*
G01D02*
X805579Y-572418D01*
G01D02*
X805552Y-572636D01*
G01D02*
X805525Y-572880D01*
G01D02*
X805507Y-573057D01*
G01X805055Y-571820D02*
Y-571819D01*
G01D02*
X805047Y-571847D01*
G01D02*
X805018Y-571921D01*
G01D02*
X804939Y-572043D01*
G01D02*
X804789Y-572166D01*
G01D02*
X804578Y-572239D01*
G01D02*
X804496Y-572244D01*
G01X805507Y-573056D02*
X805480Y-573339D01*
G01D02*
X805443Y-573757D01*
G01D02*
X805408Y-574206D01*
G01D02*
X805373Y-574682D01*
G01X805027Y-572113D02*
X805034Y-572022D01*
G01D02*
X805041Y-571947D01*
G01D02*
X805046Y-571888D01*
G01D02*
X805051Y-571845D01*
G01D02*
X805055Y-571820D01*
G01X805373Y-574682D02*
X805340Y-575182D01*
G01D02*
X805307Y-575703D01*
G01D02*
X805275Y-576242D01*
G01D02*
X805244Y-576794D01*
G01X803846Y-572087D02*
X803837Y-572220D01*
G01D02*
X803829Y-572371D01*
G01D02*
X803820Y-572541D01*
G01D02*
X803812Y-572731D01*
G01D02*
X803803Y-572941D01*
G01D02*
X803794Y-573170D01*
G01D02*
X803785Y-573418D01*
G01D02*
X803776Y-573685D01*
G01D02*
X803767Y-573972D01*
G01D02*
X803757Y-574278D01*
G01D02*
X803748Y-574602D01*
G01X805244Y-576794D02*
X805214Y-577357D01*
G01D02*
X805184Y-577926D01*
G01D02*
X805156Y-578500D01*
G01D02*
X805128Y-579074D01*
G01D02*
X805101Y-579647D01*
G01D02*
X805074Y-580216D01*
G01D02*
X805049Y-580778D01*
G01D02*
X805024Y-581331D01*
G01X806201Y-581424D02*
X806228Y-580831D01*
G01X803748Y-574602D02*
X803738Y-574946D01*
G01D02*
X803728Y-575309D01*
G01D02*
X803719Y-575690D01*
G01D02*
X803709Y-576089D01*
G01D02*
X803699Y-576506D01*
G01D02*
X803657Y-578328D01*
G01X804919Y-574979D02*
X804927Y-574678D01*
G01D02*
X804935Y-574392D01*
G01D02*
X804943Y-574120D01*
G01D02*
X804951Y-573863D01*
G01D02*
X804959Y-573621D01*
G01D02*
X804967Y-573394D01*
G01D02*
X804975Y-573181D01*
G01D02*
X804983Y-572982D01*
G01D02*
X804991Y-572799D01*
G01D02*
X804998Y-572631D01*
G01D02*
X805006Y-572478D01*
G01D02*
X805013Y-572341D01*
G01D02*
X805020Y-572219D01*
G01D02*
X805027Y-572113D01*
G01X804884Y-576331D02*
X804902Y-575626D01*
G01D02*
X804910Y-575295D01*
G01D02*
X804919Y-574979D01*
G01X805413Y-581983D02*
X805401Y-581386D01*
G01X805296Y-576599D02*
X805286Y-576166D01*
G01D02*
X805276Y-575756D01*
G01D02*
X805266Y-575368D01*
G01D02*
X805256Y-575004D01*
G01D02*
X805248Y-574713D01*
G01X805237Y-574340D02*
X805228Y-574041D01*
G01D02*
X805220Y-573764D01*
G01D02*
X805211Y-573508D01*
G01D02*
X805202Y-573272D01*
G01D02*
X805194Y-573056D01*
G01D02*
X805187Y-572859D01*
G01D02*
X805179Y-572680D01*
G01D02*
X805171Y-572517D01*
G01D02*
X805164Y-572369D01*
G01D02*
X805156Y-572237D01*
G01D02*
X805149Y-572118D01*
G01D02*
X805142Y-572012D01*
G01D02*
X805135Y-571919D01*
G01D02*
X805128Y-571836D01*
G01D02*
X805120Y-571763D01*
G01D02*
X805113Y-571698D01*
G01D02*
X805104Y-571637D01*
G01D02*
X805092Y-571575D01*
G01D02*
X805073Y-571502D01*
G01D02*
X805032Y-571400D01*
G01D02*
X804939Y-571261D01*
G01D02*
X804777Y-571135D01*
G01D02*
X804562Y-571067D01*
G01D02*
X804496Y-571063D01*
G01X803962Y-572070D02*
X803969Y-572159D01*
G01D02*
X803975Y-572262D01*
G01D02*
X803981Y-572377D01*
G01D02*
X803988Y-572505D01*
G01D02*
X803995Y-572646D01*
G01D02*
X804002Y-572801D01*
G01D02*
X804009Y-572969D01*
G01D02*
X804017Y-573151D01*
G01D02*
X804024Y-573346D01*
G01D02*
X804031Y-573556D01*
G01D02*
X804039Y-573780D01*
G01D02*
X804046Y-574018D01*
G01D02*
X804054Y-574269D01*
G01X806194Y-574520D02*
X806220Y-574877D01*
G01X805900Y-571957D02*
X805906Y-571977D01*
G01D02*
X805920Y-572029D01*
G01D02*
X805938Y-572109D01*
G01X806316Y-572241D02*
X806091Y-572164D01*
G01D02*
X805960Y-572052D01*
G01D02*
X805910Y-571978D01*
G01D02*
X805900Y-571957D01*
G01X804496Y-572244D02*
X804430Y-572241D01*
G01D02*
X804218Y-572174D01*
G01D02*
X804063Y-572053D01*
G01D02*
X803978Y-571930D01*
G01D02*
X803946Y-571851D01*
G01D02*
X803938Y-571822D01*
G01X804496Y-571063D02*
X804415Y-571069D01*
G01D02*
X804202Y-571142D01*
G01D02*
X804045Y-571270D01*
G01D02*
X803954Y-571411D01*
G01D02*
X803916Y-571514D01*
G01D02*
X803898Y-571586D01*
G01D02*
X803887Y-571649D01*
G01D02*
X803878Y-571715D01*
G01D02*
X803870Y-571788D01*
G01D02*
X803862Y-571873D01*
G01D02*
X803854Y-571972D01*
G01D02*
X803846Y-572087D01*
G01X806288Y-571071D02*
X806040Y-571166D01*
G01D02*
X805886Y-571306D01*
G01D02*
X805803Y-571436D01*
G01D02*
X805754Y-571549D01*
G01D02*
X805718Y-571659D01*
G01D02*
X805687Y-571776D01*
G01D02*
X805659Y-571907D01*
G01D02*
X805633Y-572056D01*
G01X756261Y0D02*
G03Y-7874I0J-3937D01*
G01X953111D02*
X756261D01*
G01X778187Y23622D02*
G03I-7874J0D01*
G01X797872Y448819D02*
G03X782125I-7874J0D01*
G03X797872I7874J0D01*
G01X756261Y480315D02*
G03Y472441I0J-3937D01*
G01X778187Y503937D02*
G03I-7874J0D01*
G01X756261Y960630D02*
G03Y952756I0J-3937D01*
G01X797872Y929134D02*
G03X782125I-7874J0D01*
G03X797872I7874J0D01*
G01X953111Y960630D02*
X756261D01*
G01X756751Y1387573D02*
X757921Y1386273D01*
X759286Y1385493D01*
X761041Y1385233D01*
X762796Y1385753D01*
X764161Y1386793D01*
X765136Y1388613D01*
X765331Y1390693D01*
X764941Y1392773D01*
X763966Y1394073D01*
X762601Y1395113D01*
X761236Y1395373D01*
X759871Y1395113D01*
X758116Y1394073D01*
X758701Y1400833D01*
X763966D01*
G01X860950Y-587713D02*
X829450Y-595413D01*
G01X823450Y-607113D02*
X861950D01*
G01Y-604113D02*
X829450D01*
G01X861950Y-602413D02*
X829450D01*
G01X854901Y-592326D02*
X829127Y-592717D01*
G01X811004Y-589961D02*
X811003D01*
G01X833654Y-598504D02*
X836804D01*
G01X833654Y-597407D02*
X836804D01*
G01X833654Y-597047D02*
X836804D01*
G01X829450Y-595813D02*
X809950D01*
G01X829450Y-594713D02*
X856450D01*
G01X829450Y-594313D02*
X809950D01*
G01X829450Y-592113D02*
X856450D01*
G01X823812Y-590472D02*
X825387D01*
G01Y-589674D02*
X823812D01*
G01X825387Y-589291D02*
X823812D01*
G01X825387Y-587402D02*
X823024D01*
G01X829450Y-584713D02*
X856450D01*
G01X820255Y-588780D02*
X820254D01*
G01X814087Y-588779D02*
X814086D01*
G01X820254Y-589961D02*
X820255D01*
G01X814086Y-589960D02*
X814087D01*
G01X810941Y-582615D02*
X810908Y-582030D01*
G01X807865Y-582735D02*
X807830Y-582113D01*
G01X808457Y-582677D02*
Y-585827D01*
G01X808950Y-577213D02*
Y-599213D01*
G01X809343Y-605512D02*
Y-599213D01*
G01X809950D02*
Y-594313D01*
G01Y-590613D02*
Y-557613D01*
G01X810750Y-599213D02*
Y-553713D01*
G01X807891Y-584183D02*
X807858Y-584713D01*
G01X822752Y-585816D02*
X822735Y-585169D01*
G01X821536Y-584436D02*
X821555Y-585206D01*
G01X822735Y-585169D02*
X822718Y-584469D01*
G01D02*
X822700Y-583719D01*
G01X821517Y-583607D02*
X821536Y-584436D01*
G01X822700Y-583719D02*
X822683Y-582926D01*
G01X821497Y-582725D02*
X821517Y-583607D01*
G01X822683Y-582926D02*
X822665Y-582093D01*
G01X821450Y-580512D02*
X821497Y-582725D01*
G01X820465Y-575197D02*
Y-585827D01*
G01X821450Y-605512D02*
Y-582677D01*
G01X823024Y-585827D02*
Y-587402D01*
G01X823450Y-605512D02*
Y-607113D01*
G01Y-605512D02*
Y-599213D01*
G01D02*
Y-549713D01*
G01X823812Y-571260D02*
Y-590472D01*
G01X825387Y-605512D02*
Y-599213D01*
G01Y-590472D02*
Y-571260D01*
G01X828132Y-599213D02*
Y-605512D01*
G01X829127Y-568307D02*
Y-592716D01*
G01X829450Y-604113D02*
Y-552713D01*
G01X830316Y-599213D02*
Y-605512D01*
G01X833654Y-599213D02*
Y-597047D01*
G01X834672Y-599213D02*
Y-598504D01*
G01X835786Y-599213D02*
Y-598504D01*
G01X836804Y-599213D02*
Y-597047D01*
G01X837198Y-605512D02*
Y-599213D01*
G01X839381D02*
Y-605512D01*
G01X841135D02*
Y-599213D01*
G01X854901Y-568698D02*
Y-592326D01*
G01X855227Y-568878D02*
Y-592146D01*
G01X856450Y-594713D02*
Y-592113D01*
G01Y-584713D02*
Y-582113D01*
G01X860950Y-567113D02*
Y-587713D01*
G01X861950Y-607113D02*
Y-549713D01*
G01X823166Y-583098D02*
X823193Y-581866D01*
G01X822009Y-581987D02*
X821984Y-583117D01*
G01D02*
X821968Y-583833D01*
G01X823148Y-583887D02*
X823166Y-583098D01*
G01X821968Y-583833D02*
X821952Y-584515D01*
G01X823130Y-584639D02*
X823148Y-583887D01*
G01X821952Y-584515D02*
X821937Y-585158D01*
G01D02*
X821921Y-585761D01*
G01X829450Y-602113D02*
G03X831450Y-604113I2000J0D01*
G01X854901Y-592326D02*
G03X855227Y-592146I-5J394D01*
G01D02*
G03Y-568878I-18029J11634D01*
G01X808428Y-584730D02*
G03X808595Y-582121I-285126J19561D01*
G01X810318Y-582143D02*
G03X810460Y-584728I453282J23603D01*
G01X807234Y-582121D02*
G03X807377Y-584724I451844J23517D01*
G01X810461Y-584744D02*
X810460Y-584728D01*
G01X821780Y-589187D02*
X821777Y-589204D01*
G01D02*
Y-589203D01*
G01D02*
X821786Y-589172D01*
G01D02*
X821818Y-589094D01*
G01D02*
X821903Y-588970D01*
G01D02*
X822057Y-588850D01*
G01D02*
X822269Y-588783D01*
G01D02*
X822335Y-588780D01*
G01X820269Y-583448D02*
X820248Y-583796D01*
G01D02*
X820218Y-584294D01*
G01D02*
X820188Y-584771D01*
G01D02*
X820159Y-585223D01*
G01D02*
X820130Y-585651D01*
G01D02*
X820102Y-586054D01*
G01D02*
X820074Y-586433D01*
G01D02*
X820048Y-586786D01*
G01D02*
X820021Y-587113D01*
G01D02*
X819994Y-587416D01*
G01D02*
X819969Y-587693D01*
G01D02*
X819944Y-587944D01*
G01D02*
X819919Y-588170D01*
G01D02*
X819896Y-588372D01*
G01D02*
X819872Y-588549D01*
G01D02*
X819850Y-588701D01*
G01D02*
X819829Y-588829D01*
G01D02*
X819809Y-588932D01*
G01D02*
X819792Y-589009D01*
G01D02*
X819779Y-589055D01*
G01D02*
X819778Y-589060D01*
G01X821450Y-583456D02*
X821467Y-583156D01*
G01D02*
X821493Y-582695D01*
G01D02*
X821519Y-582231D01*
G01X820326Y-582449D02*
X820293Y-583030D01*
G01D02*
X820269Y-583448D01*
G01X821921Y-585761D02*
X821906Y-586320D01*
G01D02*
X821898Y-586582D01*
G01D02*
X821891Y-586832D01*
G01D02*
X821883Y-587070D01*
G01D02*
X821876Y-587296D01*
G01D02*
X821869Y-587510D01*
G01D02*
X821862Y-587711D01*
G01D02*
X821855Y-587900D01*
G01D02*
X821848Y-588077D01*
G01D02*
X821841Y-588241D01*
G01D02*
X821833Y-588392D01*
G01D02*
X821827Y-588531D01*
G01D02*
X821820Y-588657D01*
G01D02*
X821814Y-588771D01*
G01D02*
X821807Y-588872D01*
G01D02*
X821801Y-588961D01*
G01D02*
X821795Y-589036D01*
G01D02*
X821789Y-589099D01*
G01D02*
X821784Y-589149D01*
G01D02*
X821780Y-589187D01*
G01X821555Y-585206D02*
X821564Y-585568D01*
G01D02*
X821573Y-585913D01*
G01D02*
X821582Y-586241D01*
G01D02*
X821591Y-586552D01*
G01D02*
X821599Y-586846D01*
G01D02*
X821608Y-587123D01*
G01D02*
X821617Y-587383D01*
G01D02*
X821625Y-587626D01*
G01D02*
X821633Y-587851D01*
G01D02*
X821641Y-588060D01*
G01D02*
X821649Y-588252D01*
G01D02*
X821657Y-588428D01*
G01D02*
X821665Y-588589D01*
G01D02*
X821672Y-588733D01*
G01D02*
X821680Y-588863D01*
G01D02*
X821688Y-588978D01*
G01D02*
X821695Y-589080D01*
G01D02*
X821703Y-589170D01*
G01D02*
X821710Y-589249D01*
G01D02*
X821719Y-589319D01*
G01D02*
X821727Y-589382D01*
G01D02*
X821739Y-589444D01*
G01D02*
X821757Y-589518D01*
G01D02*
X821797Y-589620D01*
G01D02*
X821889Y-589758D01*
G01D02*
X822046Y-589885D01*
G01D02*
X822257Y-589955D01*
G01D02*
X822335Y-589961D01*
G01X822894Y-589204D02*
Y-589206D01*
G01D02*
Y-589203D01*
G01D02*
X822891Y-589179D01*
G01D02*
X822886Y-589139D01*
G01D02*
X822880Y-589086D01*
G01D02*
X822875Y-589019D01*
G01D02*
X822869Y-588940D01*
G01D02*
X822862Y-588848D01*
G01D02*
X822856Y-588743D01*
G01D02*
X822849Y-588626D01*
G01D02*
X822843Y-588495D01*
G01D02*
X822835Y-588350D01*
G01D02*
X822828Y-588192D01*
G01D02*
X822821Y-588019D01*
G01D02*
X822814Y-587833D01*
G01D02*
X822807Y-587631D01*
G01D02*
X822799Y-587416D01*
G01D02*
X822791Y-587185D01*
G01D02*
X822783Y-586941D01*
G01D02*
X822776Y-586681D01*
G01D02*
X822768Y-586407D01*
G01D02*
X822760Y-586119D01*
G01D02*
X822752Y-585816D01*
G01X811483Y-589067D02*
X811473Y-589035D01*
G01D02*
X811457Y-588970D01*
G01D02*
X811437Y-588874D01*
G01D02*
X811416Y-588751D01*
G01D02*
X811393Y-588600D01*
G01D02*
X811369Y-588422D01*
G01D02*
X811344Y-588217D01*
G01D02*
X811319Y-587985D01*
G01D02*
X811292Y-587726D01*
G01D02*
X811266Y-587441D01*
G01D02*
X811239Y-587129D01*
G01D02*
X811211Y-586791D01*
G01D02*
X811183Y-586427D01*
G01D02*
X811155Y-586038D01*
G01D02*
X811126Y-585622D01*
G01D02*
X811096Y-585182D01*
G01D02*
X811067Y-584717D01*
G01D02*
X811036Y-584228D01*
G01D02*
X811005Y-583714D01*
G01D02*
X810974Y-583177D01*
G01D02*
X810941Y-582615D01*
G01X820733Y-589065D02*
X820724Y-589035D01*
G01D02*
X820708Y-588971D01*
G01D02*
X820688Y-588875D01*
G01D02*
X820666Y-588750D01*
G01D02*
X820643Y-588597D01*
G01D02*
X820619Y-588417D01*
G01D02*
X820593Y-588208D01*
G01D02*
X820568Y-587973D01*
G01D02*
X820541Y-587711D01*
G01D02*
X820515Y-587423D01*
G01D02*
X820487Y-587108D01*
G01D02*
X820459Y-586766D01*
G01D02*
X820431Y-586397D01*
G01D02*
X820402Y-586000D01*
G01D02*
X820373Y-585575D01*
G01D02*
X820343Y-585123D01*
G01D02*
X820312Y-584643D01*
G01D02*
X820281Y-584137D01*
G01D02*
X820249Y-583604D01*
G01D02*
X820216Y-583046D01*
G01D02*
X820183Y-582464D01*
G01D02*
X820149Y-581859D01*
G01X817650Y-589066D02*
X817644Y-589048D01*
G01D02*
X817630Y-588997D01*
G01D02*
X817613Y-588917D01*
G01D02*
X817593Y-588809D01*
G01D02*
X817570Y-588674D01*
G01D02*
X817547Y-588513D01*
G01D02*
X817523Y-588324D01*
G01D02*
X817498Y-588108D01*
G01D02*
X817472Y-587863D01*
G01D02*
X817446Y-587591D01*
G01D02*
X817419Y-587291D01*
G01D02*
X817391Y-586963D01*
G01D02*
X817363Y-586607D01*
G01D02*
X817335Y-586224D01*
G01D02*
X817306Y-585814D01*
G01D02*
X817276Y-585377D01*
G01D02*
X817246Y-584914D01*
G01D02*
X817215Y-584423D01*
G01D02*
X817183Y-583906D01*
G01D02*
X817151Y-583363D01*
G01D02*
X817118Y-582795D01*
G01D02*
X817084Y-582202D01*
G01X819778Y-589060D02*
X819776Y-589066D01*
G01D02*
X819794Y-589030D01*
G01D02*
X819865Y-588939D01*
G01D02*
X820038Y-588824D01*
G01D02*
X820254Y-588780D01*
G01X813612Y-589052D02*
X813608Y-589065D01*
G01D02*
X813624Y-589033D01*
G01D02*
X813691Y-588945D01*
G01D02*
X813862Y-588827D01*
G01D02*
X814086Y-588779D01*
G01X816695Y-589054D02*
X816691Y-589066D01*
G01D02*
X816707Y-589033D01*
G01D02*
X816775Y-588944D01*
G01D02*
X816946Y-588827D01*
G01D02*
X817170Y-588780D01*
G01X810530Y-589051D02*
X810524Y-589066D01*
G01D02*
X810535Y-589044D01*
G01D02*
X810585Y-588970D01*
G01D02*
X810715Y-588860D01*
G01D02*
X810939Y-588783D01*
G01D02*
X811003Y-588780D01*
G01X807858Y-584713D02*
X807829Y-585169D01*
G01D02*
X807799Y-585623D01*
G01D02*
X807769Y-586052D01*
G01D02*
X807739Y-586452D01*
G01D02*
X807711Y-586825D01*
G01D02*
X807682Y-587170D01*
G01D02*
X807655Y-587485D01*
G01D02*
X807628Y-587772D01*
G01D02*
X807601Y-588030D01*
G01D02*
X807576Y-588260D01*
G01D02*
X807551Y-588461D01*
G01D02*
X807527Y-588634D01*
G01D02*
X807504Y-588778D01*
G01D02*
X807483Y-588895D01*
G01D02*
X807464Y-588984D01*
G01D02*
X807449Y-589042D01*
G01D02*
X807448Y-589046D01*
G01X810951Y-584561D02*
X810923Y-585002D01*
G01D02*
X810895Y-585422D01*
G01D02*
X810868Y-585820D01*
G01D02*
X810841Y-586195D01*
G01D02*
X810815Y-586547D01*
G01D02*
X810789Y-586877D01*
G01D02*
X810764Y-587183D01*
G01D02*
X810739Y-587467D01*
G01D02*
X810715Y-587728D01*
G01D02*
X810691Y-587966D01*
G01D02*
X810668Y-588182D01*
G01D02*
X810644Y-588375D01*
G01D02*
X810622Y-588545D01*
G01D02*
X810601Y-588693D01*
G01D02*
X810580Y-588818D01*
G01D02*
X810561Y-588920D01*
G01D02*
X810544Y-588998D01*
G01D02*
X810530Y-589051D01*
G01X809028Y-584904D02*
X809065Y-584299D01*
G01D02*
X809104Y-583663D01*
G01D02*
X809142Y-583006D01*
G01D02*
X809180Y-582339D01*
G01X808012Y-582113D02*
X807989Y-582509D01*
G01D02*
X807956Y-583093D01*
G01D02*
X807923Y-583652D01*
G01D02*
X807891Y-584183D01*
G01X811096Y-582079D02*
X811067Y-582609D01*
G01D02*
X811037Y-583123D01*
G01D02*
X811008Y-583620D01*
G01D02*
X810979Y-584100D01*
G01D02*
X810951Y-584561D01*
G01X814190Y-581907D02*
X814152Y-582572D01*
G01D02*
X814116Y-583202D01*
G01D02*
X814081Y-583797D01*
G01D02*
X814046Y-584359D01*
G01D02*
X814013Y-584888D01*
G01D02*
X813981Y-585387D01*
G01D02*
X813949Y-585857D01*
G01D02*
X813917Y-586296D01*
G01D02*
X813887Y-586704D01*
G01D02*
X813856Y-587080D01*
G01D02*
X813826Y-587424D01*
G01D02*
X813798Y-587734D01*
G01D02*
X813769Y-588012D01*
G01D02*
X813742Y-588256D01*
G01D02*
X813716Y-588468D01*
G01D02*
X813691Y-588647D01*
G01D02*
X813668Y-588794D01*
G01D02*
X813646Y-588911D01*
G01D02*
X813627Y-588996D01*
G01D02*
X813612Y-589052D01*
G01X817247Y-582363D02*
X817210Y-583011D01*
G01D02*
X817174Y-583626D01*
G01D02*
X817139Y-584209D01*
G01D02*
X817105Y-584758D01*
G01D02*
X817072Y-585274D01*
G01D02*
X817039Y-585758D01*
G01D02*
X817007Y-586210D01*
G01D02*
X816976Y-586630D01*
G01D02*
X816945Y-587017D01*
G01D02*
X816915Y-587372D01*
G01D02*
X816885Y-587693D01*
G01D02*
X816856Y-587980D01*
G01D02*
X816828Y-588233D01*
G01D02*
X816802Y-588452D01*
G01D02*
X816776Y-588637D01*
G01D02*
X816752Y-588790D01*
G01D02*
X816730Y-588910D01*
G01D02*
X816711Y-588998D01*
G01D02*
X816695Y-589054D01*
G01X815896Y-582084D02*
X815932Y-582709D01*
G01D02*
X815968Y-583326D01*
G01D02*
X816003Y-583927D01*
G01D02*
X816039Y-584508D01*
G01D02*
X816073Y-585062D01*
G01D02*
X816108Y-585585D01*
G01D02*
X816142Y-586074D01*
G01D02*
X816174Y-586526D01*
G01D02*
X816207Y-586941D01*
G01D02*
X816238Y-587319D01*
G01D02*
X816269Y-587664D01*
G01D02*
X816298Y-587974D01*
G01D02*
X816328Y-588252D01*
G01D02*
X816357Y-588499D01*
G01D02*
X816385Y-588717D01*
G01D02*
X816414Y-588908D01*
G01D02*
X816442Y-589073D01*
G01D02*
X816471Y-589216D01*
G01D02*
X816503Y-589343D01*
G01D02*
X816539Y-589459D01*
G01D02*
X816588Y-589576D01*
G01D02*
X816669Y-589709D01*
G01D02*
X816823Y-589854D01*
G01D02*
X817074Y-589953D01*
G01D02*
X817170Y-589961D01*
G01X812817Y-582152D02*
X812856Y-582842D01*
G01D02*
X812886Y-583359D01*
G01X819001Y-582448D02*
X819036Y-583067D01*
G01D02*
X819072Y-583671D01*
G01D02*
X819107Y-584253D01*
G01D02*
X819141Y-584809D01*
G01D02*
X819175Y-585334D01*
G01D02*
X819208Y-585826D01*
G01D02*
X819240Y-586281D01*
G01D02*
X819272Y-586702D01*
G01D02*
X819302Y-587089D01*
G01D02*
X819332Y-587443D01*
G01D02*
X819362Y-587765D01*
G01D02*
X819391Y-588056D01*
G01D02*
X819419Y-588317D01*
G01D02*
X819447Y-588550D01*
G01D02*
X819475Y-588756D01*
G01D02*
X819502Y-588937D01*
G01D02*
X819530Y-589093D01*
G01D02*
X819558Y-589231D01*
G01D02*
X819589Y-589354D01*
G01D02*
X819626Y-589467D01*
G01D02*
X819675Y-589582D01*
G01D02*
X819757Y-589713D01*
G01D02*
X819911Y-589856D01*
G01D02*
X820160Y-589953D01*
G01D02*
X820255Y-589961D01*
G01X806641Y-581979D02*
X806677Y-582609D01*
G01D02*
X806713Y-583243D01*
G01D02*
X806750Y-583869D01*
G01D02*
X806787Y-584478D01*
G01X809731Y-582100D02*
X809768Y-582749D01*
G01D02*
X809804Y-583385D01*
G01D02*
X809841Y-583999D01*
G01D02*
X809876Y-584584D01*
G01X814067Y-583353D02*
X814032Y-582754D01*
G01D02*
X813989Y-581983D01*
G01X812886Y-583359D02*
X812913Y-583815D01*
G01D02*
X812948Y-584404D01*
G01D02*
X812983Y-584962D01*
G01D02*
X813018Y-585488D01*
G01D02*
X813052Y-585981D01*
G01D02*
X813085Y-586441D01*
G01D02*
X813117Y-586866D01*
G01D02*
X813149Y-587257D01*
G01D02*
X813180Y-587613D01*
G01D02*
X813211Y-587935D01*
G01D02*
X813241Y-588222D01*
G01D02*
X813271Y-588478D01*
G01D02*
X813300Y-588703D01*
G01D02*
X813329Y-588899D01*
G01D02*
X813358Y-589069D01*
G01D02*
X813388Y-589215D01*
G01D02*
X813419Y-589344D01*
G01D02*
X813456Y-589462D01*
G01D02*
X813506Y-589580D01*
G01D02*
X813590Y-589715D01*
G01D02*
X813746Y-589858D01*
G01D02*
X813995Y-589953D01*
G01D02*
X814087Y-589960D01*
G01X807998Y-584940D02*
X807966Y-584432D01*
G01D02*
X807933Y-583895D01*
G01D02*
X807900Y-583329D01*
G01D02*
X807865Y-582735D01*
G01X806787Y-584478D02*
X806824Y-585058D01*
G01D02*
X806859Y-585601D01*
G01D02*
X806894Y-586101D01*
G01D02*
X806927Y-586556D01*
G01D02*
X806959Y-586968D01*
G01D02*
X806990Y-587341D01*
G01D02*
X807020Y-587677D01*
G01D02*
X807049Y-587980D01*
G01D02*
X807078Y-588250D01*
G01D02*
X807106Y-588491D01*
G01D02*
X807134Y-588704D01*
G01D02*
X807161Y-588891D01*
G01D02*
X807189Y-589055D01*
G01D02*
X807218Y-589200D01*
G01D02*
X807248Y-589327D01*
G01D02*
X807283Y-589444D01*
G01D02*
X807331Y-589561D01*
G01D02*
X807409Y-589696D01*
G01D02*
X807560Y-589844D01*
G01D02*
X807815Y-589951D01*
G01D02*
X807920Y-589960D01*
G01X809876Y-584584D02*
X809911Y-585132D01*
G01D02*
X809945Y-585642D01*
G01D02*
X809978Y-586115D01*
G01D02*
X810010Y-586551D01*
G01D02*
X810041Y-586952D01*
G01D02*
X810071Y-587320D01*
G01D02*
X810101Y-587655D01*
G01D02*
X810130Y-587960D01*
G01D02*
X810159Y-588235D01*
G01D02*
X810188Y-588480D01*
G01D02*
X810216Y-588697D01*
G01D02*
X810244Y-588887D01*
G01D02*
X810272Y-589053D01*
G01D02*
X810301Y-589199D01*
G01D02*
X810331Y-589327D01*
G01D02*
X810367Y-589444D01*
G01D02*
X810413Y-589560D01*
G01D02*
X810491Y-589694D01*
G01D02*
X810641Y-589843D01*
G01D02*
X810896Y-589951D01*
G01D02*
X811004Y-589961D01*
G01X808400Y-589066D02*
X808389Y-589033D01*
G01D02*
X808373Y-588965D01*
G01D02*
X808353Y-588865D01*
G01D02*
X808331Y-588736D01*
G01D02*
X808307Y-588579D01*
G01D02*
X808282Y-588394D01*
G01D02*
X808257Y-588180D01*
G01D02*
X808230Y-587937D01*
G01D02*
X808204Y-587666D01*
G01D02*
X808176Y-587365D01*
G01D02*
X808148Y-587035D01*
G01D02*
X808119Y-586675D01*
G01D02*
X808090Y-586286D01*
G01D02*
X808059Y-585867D01*
G01D02*
X808029Y-585419D01*
G01D02*
X807998Y-584940D01*
G01X814566Y-589066D02*
Y-589067D01*
G01D02*
X814561Y-589050D01*
G01D02*
X814546Y-588997D01*
G01D02*
X814528Y-588914D01*
G01D02*
X814508Y-588802D01*
G01D02*
X814485Y-588662D01*
G01D02*
X814461Y-588494D01*
G01D02*
X814437Y-588300D01*
G01D02*
X814411Y-588076D01*
G01D02*
X814385Y-587824D01*
G01D02*
X814358Y-587543D01*
G01D02*
X814331Y-587233D01*
G01D02*
X814302Y-586894D01*
G01D02*
X814274Y-586526D01*
G01D02*
X814244Y-586130D01*
G01D02*
X814215Y-585706D01*
G01D02*
X814184Y-585254D01*
G01D02*
X814153Y-584776D01*
G01D02*
X814122Y-584272D01*
G01D02*
X814090Y-583744D01*
G01D02*
X814067Y-583353D01*
G01X807448Y-589046D02*
X807442Y-589065D01*
G01D02*
X807451Y-589045D01*
G01D02*
X807497Y-588976D01*
G01D02*
X807616Y-588870D01*
G01D02*
X807833Y-588786D01*
G01D02*
X807920Y-588779D01*
G01X822335Y-588780D02*
X822419Y-588786D01*
G01D02*
X822628Y-588858D01*
G01D02*
X822778Y-588981D01*
G01D02*
X822859Y-589106D01*
G01D02*
X822888Y-589180D01*
G01D02*
X822894Y-589204D01*
G01X807920Y-588779D02*
X807996Y-588784D01*
G01D02*
X808221Y-588867D01*
G01D02*
X808348Y-588981D01*
G01D02*
X808393Y-589052D01*
G01D02*
X808400Y-589066D01*
G01X811004Y-588780D02*
X811078Y-588785D01*
G01D02*
X811303Y-588867D01*
G01D02*
X811431Y-588981D01*
G01D02*
X811476Y-589052D01*
G01D02*
X811483Y-589067D01*
G01X817170Y-588780D02*
X817244Y-588785D01*
G01D02*
X817463Y-588863D01*
G01D02*
X817589Y-588971D01*
G01D02*
X817639Y-589044D01*
G01D02*
X817650Y-589066D01*
G01X814087Y-588779D02*
X814156Y-588784D01*
G01D02*
X814372Y-588858D01*
G01D02*
X814502Y-588967D01*
G01D02*
X814554Y-589042D01*
G01D02*
X814566Y-589066D01*
G01X820255Y-588780D02*
X820323Y-588784D01*
G01D02*
X820547Y-588862D01*
G01D02*
X820678Y-588976D01*
G01D02*
X820726Y-589048D01*
G01D02*
X820733Y-589065D01*
G01X822335Y-589961D02*
X822404Y-589956D01*
G01D02*
X822619Y-589888D01*
G01D02*
X822781Y-589759D01*
G01D02*
X822876Y-589617D01*
G01D02*
X822915Y-589512D01*
G01D02*
X822933Y-589441D01*
G01D02*
X822944Y-589378D01*
G01D02*
X822953Y-589315D01*
G01D02*
X822961Y-589244D01*
G01D02*
X822969Y-589165D01*
G01D02*
X822976Y-589075D01*
G01D02*
X822984Y-588973D01*
G01D02*
X822991Y-588857D01*
G01D02*
X822999Y-588728D01*
G01D02*
X823006Y-588585D01*
G01D02*
X823014Y-588426D01*
G01D02*
X823022Y-588253D01*
G01D02*
X823030Y-588065D01*
G01D02*
X823038Y-587861D01*
G01D02*
X823046Y-587642D01*
G01D02*
X823054Y-587407D01*
G01D02*
X823062Y-587157D01*
G01D02*
X823070Y-586891D01*
G01D02*
X823079Y-586611D01*
G01D02*
X823087Y-586316D01*
G01D02*
X823096Y-586007D01*
G01D02*
X823104Y-585683D01*
G01D02*
X823113Y-585348D01*
G01D02*
X823130Y-584639D01*
G01X807920Y-589960D02*
X808001Y-589955D01*
G01D02*
X808256Y-589860D01*
G01D02*
X808419Y-589712D01*
G01D02*
X808504Y-589575D01*
G01D02*
X808554Y-589455D01*
G01D02*
X808591Y-589335D01*
G01D02*
X808623Y-589203D01*
G01D02*
X808653Y-589052D01*
G01D02*
X808682Y-588880D01*
G01D02*
X808710Y-588683D01*
G01D02*
X808739Y-588460D01*
G01D02*
X808768Y-588208D01*
G01D02*
X808797Y-587925D01*
G01D02*
X808828Y-587609D01*
G01D02*
X808858Y-587261D01*
G01D02*
X808890Y-586875D01*
G01D02*
X808922Y-586450D01*
G01D02*
X808956Y-585982D01*
G01D02*
X808991Y-585467D01*
G01D02*
X809028Y-584904D01*
G01X811003Y-589961D02*
X811091Y-589954D01*
G01D02*
X811350Y-589854D01*
G01D02*
X811506Y-589707D01*
G01D02*
X811588Y-589573D01*
G01D02*
X811636Y-589456D01*
G01D02*
X811672Y-589342D01*
G01D02*
X811702Y-589217D01*
G01D02*
X811731Y-589077D01*
G01D02*
X811759Y-588918D01*
G01D02*
X811786Y-588739D01*
G01D02*
X811813Y-588536D01*
G01D02*
X811840Y-588309D01*
G01D02*
X811867Y-588056D01*
G01D02*
X811895Y-587777D01*
G01D02*
X811923Y-587472D01*
G01D02*
X811951Y-587140D01*
G01D02*
X811980Y-586783D01*
G01D02*
X812009Y-586399D01*
G01D02*
X812038Y-585990D01*
G01D02*
X812069Y-585553D01*
G01D02*
X812099Y-585088D01*
G01D02*
X812130Y-584593D01*
G01D02*
X812162Y-584069D01*
G01D02*
X812195Y-583515D01*
G01D02*
X812230Y-582930D01*
G01D02*
X812265Y-582315D01*
G01X820254Y-589961D02*
X820487Y-589914D01*
G01D02*
X820702Y-589770D01*
G01D02*
X820812Y-589623D01*
G01D02*
X820872Y-589497D01*
G01D02*
X820912Y-589380D01*
G01D02*
X820944Y-589256D01*
G01D02*
X820974Y-589117D01*
G01D02*
X821002Y-588959D01*
G01D02*
X821030Y-588780D01*
G01D02*
X821058Y-588576D01*
G01D02*
X821086Y-588346D01*
G01D02*
X821114Y-588089D01*
G01D02*
X821143Y-587803D01*
G01D02*
X821172Y-587486D01*
G01D02*
X821202Y-587140D01*
G01D02*
X821232Y-586763D01*
G01D02*
X821263Y-586356D01*
G01D02*
X821294Y-585918D01*
G01D02*
X821326Y-585450D01*
G01D02*
X821358Y-584951D01*
G01D02*
X821392Y-584422D01*
G01D02*
X821425Y-583866D01*
G01D02*
X821450Y-583455D01*
G01X814086Y-589960D02*
X814325Y-589912D01*
G01D02*
X814539Y-589765D01*
G01D02*
X814647Y-589619D01*
G01D02*
X814706Y-589491D01*
G01D02*
X814747Y-589371D01*
G01D02*
X814780Y-589241D01*
G01D02*
X814811Y-589094D01*
G01D02*
X814841Y-588922D01*
G01D02*
X814871Y-588721D01*
G01D02*
X814902Y-588488D01*
G01D02*
X814933Y-588221D01*
G01D02*
X814964Y-587920D01*
G01D02*
X814996Y-587582D01*
G01D02*
X815029Y-587205D01*
G01D02*
X815063Y-586788D01*
G01D02*
X815097Y-586330D01*
G01D02*
X815133Y-585827D01*
G01D02*
X815170Y-585280D01*
G01D02*
X815207Y-584693D01*
G01D02*
X815246Y-584070D01*
G01D02*
X815284Y-583419D01*
G01D02*
X815323Y-582748D01*
G01D02*
X815362Y-582067D01*
G01X817170Y-589961D02*
X817409Y-589912D01*
G01D02*
X817622Y-589766D01*
G01D02*
X817730Y-589620D01*
G01D02*
X817789Y-589494D01*
G01D02*
X817828Y-589378D01*
G01D02*
X817861Y-589256D01*
G01D02*
X817890Y-589119D01*
G01D02*
X817918Y-588962D01*
G01D02*
X817946Y-588783D01*
G01D02*
X817974Y-588581D01*
G01D02*
X818002Y-588353D01*
G01D02*
X818030Y-588098D01*
G01D02*
X818058Y-587815D01*
G01D02*
X818087Y-587504D01*
G01D02*
X818116Y-587165D01*
G01D02*
X818146Y-586797D01*
G01D02*
X818176Y-586402D01*
G01D02*
X818206Y-585978D01*
G01D02*
X818237Y-585525D01*
G01D02*
X818269Y-585043D01*
G01D02*
X818301Y-584529D01*
G01D02*
X818334Y-583984D01*
G01D02*
X818369Y-583405D01*
G01D02*
X818404Y-582793D01*
G01D02*
X818441Y-582146D01*
G01X841135Y-599213D02*
X929027D01*
G01X841135Y-605512D02*
X929027D01*
G01X829450Y-582113D02*
X856450D01*
G01X825387Y-582012D02*
X823812D01*
G01X821450Y-580512D02*
X823812D01*
G01X861950Y-580213D02*
X829450D01*
G01X825387Y-580043D02*
X823812D01*
G01X825387Y-579134D02*
X823812D01*
G01X825387Y-578740D02*
X823418D01*
G01X819481Y-578346D02*
X825387D01*
G01X829450Y-574713D02*
X856450D01*
G01X825387Y-573228D02*
X823812D01*
G01X829450Y-572113D02*
X856450D01*
G01X823812Y-571260D02*
X825387D01*
G01X829450Y-564713D02*
X856450D01*
G01X829450Y-562113D02*
X856450D01*
G01X809463Y-571065D02*
X809462D01*
G01X812546D02*
X812545D01*
G01X854901Y-568698D02*
X829127Y-568307D01*
G01X829450Y-554413D02*
X861950D01*
G01Y-552713D02*
X829450D01*
G01Y-561013D02*
X860950Y-567113D01*
G01X807391Y-574713D02*
X807360Y-574297D01*
G01X812500Y-576579D02*
X812538Y-577213D01*
G01X807830Y-582113D02*
X807794Y-581474D01*
G01X809694Y-581448D02*
X809731Y-582100D01*
G01X807794Y-581474D02*
X807684Y-579494D01*
G01X810908Y-582030D02*
X810766Y-579476D01*
G01X812668Y-579481D02*
X812778Y-581467D01*
G01X815725Y-579008D02*
X815861Y-581456D01*
G01X818826Y-579304D02*
X818965Y-581817D01*
G01X811410Y-578346D02*
Y-575197D01*
G01X808059Y-581261D02*
X808012Y-582113D01*
G01X808288Y-577213D02*
X808243Y-577983D01*
G01X811371Y-577213D02*
X811330Y-577906D01*
G01X812515Y-577840D02*
X812552Y-577213D01*
G01X822553D02*
X822539Y-576701D01*
G01X822500Y-574839D02*
X822516Y-575422D01*
G01D02*
X822532Y-576057D01*
G01X823726Y-576596D02*
X823707Y-575824D01*
G01X822532Y-576057D02*
X822548Y-576738D01*
G01D02*
X822565Y-577463D01*
G01X823755Y-577862D02*
X823726Y-576596D01*
G01X822565Y-577463D02*
X822582Y-578227D01*
G01X821430Y-579590D02*
X821450Y-580512D01*
G01X822582Y-578227D02*
X822608Y-579434D01*
G01X823785Y-579239D02*
X823755Y-577862D01*
G01X822608Y-579434D02*
X822626Y-580270D01*
G01X822665Y-582093D02*
X822612Y-579631D01*
G01X823812Y-580512D02*
X823785Y-579239D01*
G01X819481Y-578346D02*
Y-575197D01*
G01X823418D02*
Y-578740D01*
G01X844944Y-577213D02*
Y-549713D01*
G01X846073D02*
Y-577213D01*
G01X847844Y-549713D02*
Y-577213D01*
G01X856450Y-574713D02*
Y-572113D01*
G01Y-564713D02*
Y-562113D01*
G01X823193Y-581866D02*
X823263Y-578551D01*
G01X822087Y-578306D02*
X822009Y-581987D01*
G01X823263Y-578551D02*
X823280Y-577774D01*
G01D02*
X823297Y-577035D01*
G01D02*
X823314Y-576340D01*
G01D02*
X823330Y-575692D01*
G01D02*
X823345Y-575092D01*
G01X821641Y-579933D02*
X821752Y-577773D01*
G01X820611Y-576990D02*
X820449Y-580139D01*
G01X822040Y-580511D02*
G03X821967Y-577205I-736591J-14611D01*
G01X810057Y-577198D02*
G03X809950Y-575358I-301933J-16635D01*
G01D02*
G03X809907Y-574693I-175135J-10991D01*
G01X855227Y-568878D02*
G03X854901Y-568698I-331J-214D01*
G01X831450Y-552713D02*
G03X829450Y-554713I0J-2000D01*
G01X810318Y-582143D02*
X810317Y-582120D01*
G01X823485Y-571820D02*
Y-571819D01*
G01D02*
X823478Y-571846D01*
G01D02*
X823448Y-571920D01*
G01D02*
X823369Y-572043D01*
G01D02*
X823219Y-572165D01*
G01D02*
X823009Y-572238D01*
G01D02*
X822926Y-572244D01*
G01X823446Y-572282D02*
X823453Y-572176D01*
G01D02*
X823459Y-572083D01*
G01D02*
X823465Y-572003D01*
G01D02*
X823471Y-571936D01*
G01D02*
X823477Y-571883D01*
G01D02*
X823481Y-571844D01*
G01D02*
X823485Y-571820D01*
G01X821519Y-582231D02*
X821544Y-581768D01*
G01D02*
X821569Y-581304D01*
G01D02*
X821593Y-580843D01*
G01D02*
X821641Y-579933D01*
G01X821752Y-577773D02*
X821793Y-576976D01*
G01D02*
X821813Y-576595D01*
G01D02*
X821833Y-576226D01*
G01D02*
X821852Y-575871D01*
G01D02*
X821871Y-575529D01*
G01D02*
X821890Y-575201D01*
G01D02*
X821908Y-574888D01*
G01D02*
X821926Y-574589D01*
G01D02*
X821943Y-574304D01*
G01D02*
X821961Y-574035D01*
G01D02*
X821978Y-573781D01*
G01D02*
X821994Y-573542D01*
G01D02*
X822010Y-573319D01*
G01D02*
X822026Y-573112D01*
G01D02*
X822041Y-572920D01*
G01D02*
X822056Y-572744D01*
G01D02*
X822071Y-572584D01*
G01D02*
X822085Y-572440D01*
G01D02*
X822099Y-572311D01*
G01D02*
X822112Y-572198D01*
G01D02*
X822125Y-572101D01*
G01D02*
X822137Y-572021D01*
G01D02*
X822147Y-571958D01*
G01D02*
X822156Y-571915D01*
G01D02*
X822157Y-571910D01*
G01X820449Y-580139D02*
X820419Y-580708D01*
G01D02*
X820389Y-581285D01*
G01D02*
X820358Y-581867D01*
G01D02*
X820326Y-582449D01*
G01X823345Y-575092D02*
X823361Y-574541D01*
G01D02*
X823368Y-574283D01*
G01D02*
X823376Y-574039D01*
G01D02*
X823383Y-573807D01*
G01D02*
X823390Y-573588D01*
G01D02*
X823398Y-573381D01*
G01D02*
X823405Y-573187D01*
G01D02*
X823412Y-573005D01*
G01D02*
X823419Y-572835D01*
G01D02*
X823426Y-572678D01*
G01D02*
X823433Y-572533D01*
G01D02*
X823439Y-572401D01*
G01D02*
X823446Y-572282D01*
G01X822612Y-579631D02*
X822600Y-579112D01*
G01D02*
X822588Y-578603D01*
G01D02*
X822576Y-578106D01*
G01D02*
X822563Y-577622D01*
G01D02*
X822553Y-577213D01*
G01X823707Y-575824D02*
X823698Y-575462D01*
G01D02*
X823689Y-575117D01*
G01D02*
X823680Y-574787D01*
G01D02*
X823671Y-574476D01*
G01D02*
X823662Y-574181D01*
G01D02*
X823654Y-573904D01*
G01D02*
X823645Y-573644D01*
G01D02*
X823637Y-573401D01*
G01D02*
X823629Y-573175D01*
G01D02*
X823620Y-572965D01*
G01D02*
X823613Y-572773D01*
G01D02*
X823605Y-572596D01*
G01D02*
X823597Y-572436D01*
G01D02*
X823589Y-572292D01*
G01D02*
X823581Y-572162D01*
G01D02*
X823574Y-572046D01*
G01D02*
X823567Y-571944D01*
G01D02*
X823559Y-571854D01*
G01D02*
X823552Y-571775D01*
G01D02*
X823543Y-571706D01*
G01D02*
X823534Y-571642D01*
G01D02*
X823523Y-571580D01*
G01D02*
X823504Y-571507D01*
G01D02*
X823465Y-571404D01*
G01X821366Y-576991D02*
X821379Y-577482D01*
G01D02*
X821392Y-577990D01*
G01D02*
X821405Y-578512D01*
G01D02*
X821417Y-579046D01*
G01D02*
X821430Y-579590D01*
G01X822539Y-576701D02*
X822526Y-576266D01*
G01D02*
X822513Y-575850D01*
G01D02*
X822500Y-575452D01*
G01D02*
X822488Y-575074D01*
G01D02*
X822475Y-574715D01*
G01D02*
X822462Y-574378D01*
G01D02*
X822449Y-574061D01*
G01D02*
X822436Y-573765D01*
G01D02*
X822423Y-573490D01*
G01D02*
X822410Y-573236D01*
G01D02*
X822397Y-573002D01*
G01D02*
X822384Y-572789D01*
G01D02*
X822371Y-572594D01*
G01D02*
X822358Y-572418D01*
G01D02*
X822345Y-572259D01*
G01D02*
X822331Y-572117D01*
G01D02*
X822319Y-571991D01*
G01D02*
X822305Y-571879D01*
G01D02*
X822291Y-571780D01*
G01D02*
X822275Y-571690D01*
G01D02*
X822256Y-571604D01*
G01D02*
X822230Y-571516D01*
G01D02*
X822187Y-571413D01*
G01D02*
X822103Y-571283D01*
G01D02*
X821945Y-571149D01*
G01D02*
X821715Y-571069D01*
G01D02*
X821637Y-571064D01*
G01X820149Y-581859D02*
X820078Y-580589D01*
G01D02*
X820004Y-579259D01*
G01D02*
X819966Y-578582D01*
G01D02*
X819927Y-577902D01*
G01D02*
X819887Y-577226D01*
G01D02*
X819848Y-576568D01*
G01D02*
X819808Y-575938D01*
G01D02*
X819769Y-575346D01*
G01D02*
X819731Y-574802D01*
G01D02*
X819694Y-574310D01*
G01D02*
X819659Y-573871D01*
G01D02*
X819625Y-573481D01*
G01D02*
X819593Y-573136D01*
G01D02*
X819561Y-572830D01*
G01D02*
X819530Y-572562D01*
G01D02*
X819500Y-572328D01*
G01D02*
X819470Y-572126D01*
G01D02*
X819441Y-571951D01*
G01D02*
X819410Y-571799D01*
G01D02*
X819376Y-571667D01*
G01D02*
X819336Y-571543D01*
G01D02*
X819277Y-571414D01*
G01D02*
X819170Y-571265D01*
G01D02*
X818955Y-571115D01*
G01D02*
X818712Y-571065D01*
G01X810222Y-572135D02*
X810194Y-571969D01*
G01D02*
X810165Y-571823D01*
G01D02*
X810134Y-571695D01*
G01D02*
X810098Y-571577D01*
G01D02*
X810050Y-571459D01*
G01D02*
X809970Y-571324D01*
G01X807137Y-572122D02*
X807109Y-571961D01*
G01D02*
X807081Y-571817D01*
G01D02*
X807050Y-571691D01*
G01D02*
X807015Y-571574D01*
G01D02*
X806967Y-571456D01*
G01D02*
X806885Y-571320D01*
G01D02*
X806728Y-571171D01*
G01D02*
X806468Y-571070D01*
G01D02*
X806380Y-571064D01*
G01X822367Y-571817D02*
Y-571818D01*
G01D02*
X822370Y-571836D01*
G01D02*
X822374Y-571869D01*
G01D02*
X822379Y-571916D01*
G01D02*
X822385Y-571975D01*
G01D02*
X822390Y-572045D01*
G01D02*
X822396Y-572126D01*
G01D02*
X822402Y-572220D01*
G01D02*
X822408Y-572324D01*
G01D02*
X822415Y-572441D01*
G01D02*
X822421Y-572569D01*
G01D02*
X822428Y-572710D01*
G01D02*
X822435Y-572864D01*
G01D02*
X822441Y-573031D01*
G01D02*
X822448Y-573211D01*
G01D02*
X822456Y-573404D01*
G01D02*
X822463Y-573609D01*
G01D02*
X822470Y-573829D01*
G01D02*
X822477Y-574061D01*
G01D02*
X822485Y-574307D01*
G01D02*
X822493Y-574566D01*
G01D02*
X822500Y-574839D01*
G01X809009Y-572056D02*
X809029Y-572153D01*
G01D02*
X809051Y-572278D01*
G01D02*
X809074Y-572431D01*
G01D02*
X809098Y-572610D01*
G01D02*
X809123Y-572816D01*
G01D02*
X809148Y-573047D01*
G01D02*
X809174Y-573306D01*
G01D02*
X809201Y-573590D01*
G01D02*
X809228Y-573900D01*
G01D02*
X809255Y-574236D01*
G01D02*
X809283Y-574597D01*
G01X821110Y-571883D02*
X821114Y-571902D01*
G01D02*
X821122Y-571945D01*
G01D02*
X821131Y-572007D01*
G01D02*
X821142Y-572090D01*
G01D02*
X821153Y-572192D01*
G01D02*
X821165Y-572314D01*
G01D02*
X821177Y-572459D01*
G01D02*
X821190Y-572625D01*
G01D02*
X821203Y-572815D01*
G01D02*
X821216Y-573028D01*
G01D02*
X821229Y-573266D01*
G01D02*
X821243Y-573529D01*
G01D02*
X821256Y-573817D01*
G01D02*
X821270Y-574130D01*
G01D02*
X821284Y-574469D01*
G01D02*
X821298Y-574832D01*
G01D02*
X821311Y-575219D01*
G01D02*
X821325Y-575630D01*
G01D02*
X821339Y-576063D01*
G01D02*
X821352Y-576517D01*
G01D02*
X821366Y-576991D01*
G01X808983Y-571959D02*
X808993Y-571989D01*
G01D02*
X809009Y-572056D01*
G01X815151Y-571962D02*
X815154Y-571970D01*
G01D02*
X815167Y-572019D01*
G01D02*
X815185Y-572101D01*
G01D02*
X815206Y-572212D01*
G01D02*
X815229Y-572350D01*
G01D02*
X815252Y-572514D01*
G01D02*
X815276Y-572702D01*
G01D02*
X815301Y-572916D01*
G01D02*
X815326Y-573154D01*
G01D02*
X815352Y-573417D01*
G01D02*
X815378Y-573704D01*
G01D02*
X815404Y-574017D01*
G01D02*
X815431Y-574354D01*
G01D02*
X815458Y-574714D01*
G01D02*
X815486Y-575098D01*
G01D02*
X815514Y-575506D01*
G01D02*
X815542Y-575935D01*
G01D02*
X815571Y-576388D01*
G01D02*
X815600Y-576865D01*
G01X818234Y-571961D02*
X818239Y-571975D01*
G01D02*
X818253Y-572027D01*
G01D02*
X818271Y-572112D01*
G01D02*
X818293Y-572226D01*
G01D02*
X818315Y-572367D01*
G01D02*
X818339Y-572534D01*
G01D02*
X818363Y-572728D01*
G01D02*
X818388Y-572948D01*
G01D02*
X818413Y-573193D01*
G01D02*
X818440Y-573465D01*
G01D02*
X818466Y-573762D01*
G01D02*
X818493Y-574085D01*
G01D02*
X818521Y-574433D01*
G01D02*
X818548Y-574807D01*
G01D02*
X818577Y-575205D01*
G01D02*
X818606Y-575628D01*
G01D02*
X818635Y-576076D01*
G01D02*
X818665Y-576550D01*
G01D02*
X818695Y-577049D01*
G01X817084Y-582202D02*
X817050Y-581586D01*
G01X812067Y-571960D02*
Y-571961D01*
G01D02*
X812077Y-571993D01*
G01D02*
X812094Y-572062D01*
G01D02*
X812114Y-572164D01*
G01D02*
X812137Y-572295D01*
G01D02*
X812160Y-572454D01*
G01D02*
X812185Y-572642D01*
G01D02*
X812211Y-572857D01*
G01D02*
X812237Y-573100D01*
G01D02*
X812264Y-573370D01*
G01D02*
X812291Y-573670D01*
G01D02*
X812319Y-573998D01*
G01D02*
X812348Y-574356D01*
G01D02*
X812377Y-574742D01*
G01D02*
X812407Y-575158D01*
G01D02*
X812437Y-575603D01*
G01D02*
X812468Y-576077D01*
G01D02*
X812500Y-576579D01*
G01X816101Y-571977D02*
X816107Y-571959D01*
G01D02*
X816097Y-571980D01*
G01D02*
X816049Y-572052D01*
G01D02*
X815924Y-572161D01*
G01D02*
X815705Y-572240D01*
G01D02*
X815629Y-572246D01*
G01X819184Y-571980D02*
X819191Y-571959D01*
G01D02*
X819182Y-571978D01*
G01D02*
X819136Y-572048D01*
G01D02*
X819017Y-572154D01*
G01D02*
X818805Y-572237D01*
G01D02*
X818712Y-572246D01*
G01X813016Y-571983D02*
X813023Y-571960D01*
G01D02*
X813017Y-571975D01*
G01D02*
X812973Y-572043D01*
G01D02*
X812852Y-572153D01*
G01D02*
X812630Y-572239D01*
G01D02*
X812545Y-572246D01*
G01X822157Y-571910D02*
X822161Y-571894D01*
G01D02*
X822157Y-571903D01*
G01D02*
X822135Y-571952D01*
G01D02*
X822072Y-572046D01*
G01D02*
X821939Y-572160D01*
G01D02*
X821730Y-572237D01*
G01D02*
X821637Y-572245D01*
G01X806815Y-572138D02*
X806835Y-572046D01*
G01D02*
X806850Y-571984D01*
G01D02*
X806855Y-571969D01*
G01X809897Y-572141D02*
X809916Y-572050D01*
G01D02*
X809932Y-571988D01*
G01D02*
X809933Y-571984D01*
G01X808728Y-571983D02*
X808700Y-572152D01*
G01D02*
X808672Y-572344D01*
G01D02*
X808644Y-572563D01*
G01D02*
X808616Y-572808D01*
G01D02*
X808587Y-573080D01*
G01D02*
X808559Y-573380D01*
G01D02*
X808530Y-573707D01*
G01D02*
X808500Y-574061D01*
G01D02*
X808470Y-574444D01*
G01X806684Y-573137D02*
X806699Y-572993D01*
G01D02*
X806723Y-572776D01*
G01D02*
X806747Y-572580D01*
G01D02*
X806771Y-572407D01*
G01D02*
X806794Y-572259D01*
G01D02*
X806815Y-572138D01*
G01X809624Y-574832D02*
X809652Y-574461D01*
G01D02*
X809679Y-574115D01*
G01D02*
X809706Y-573794D01*
G01D02*
X809732Y-573499D01*
G01D02*
X809757Y-573230D01*
G01D02*
X809783Y-572986D01*
G01D02*
X809807Y-572767D01*
G01D02*
X809831Y-572572D01*
G01D02*
X809854Y-572403D01*
G01D02*
X809876Y-572259D01*
G01D02*
X809897Y-572141D01*
G01X808470Y-574444D02*
X808440Y-574854D01*
G01D02*
X808409Y-575294D01*
G01D02*
X808378Y-575766D01*
G01D02*
X808346Y-576269D01*
G01D02*
X808313Y-576806D01*
G01D02*
X808288Y-577213D01*
G01X806542Y-574877D02*
X806579Y-574364D01*
G01D02*
X806616Y-573883D01*
G01D02*
X806654Y-573441D01*
G01D02*
X806684Y-573137D01*
G01X812552Y-577213D02*
X812582Y-576717D01*
G01D02*
X812615Y-576197D01*
G01D02*
X812647Y-575705D01*
G01D02*
X812678Y-575241D01*
G01D02*
X812709Y-574806D01*
G01D02*
X812739Y-574402D01*
G01D02*
X812769Y-574028D01*
G01D02*
X812798Y-573685D01*
G01D02*
X812827Y-573373D01*
G01D02*
X812854Y-573093D01*
G01D02*
X812881Y-572843D01*
G01D02*
X812907Y-572624D01*
G01D02*
X812933Y-572435D01*
G01D02*
X812957Y-572277D01*
G01D02*
X812979Y-572149D01*
G01D02*
X812999Y-572052D01*
G01D02*
X813015Y-571988D01*
G01D02*
X813016Y-571983D01*
G01X817565Y-576756D02*
X817526Y-577421D01*
G01D02*
X817485Y-578113D01*
G01D02*
X817445Y-578825D01*
G01D02*
X817404Y-579546D01*
G01D02*
X817364Y-580269D01*
G01X815616Y-577545D02*
X815649Y-576989D01*
G01D02*
X815681Y-576461D01*
G01D02*
X815713Y-575963D01*
G01D02*
X815744Y-575493D01*
G01D02*
X815775Y-575052D01*
G01D02*
X815805Y-574639D01*
G01D02*
X815834Y-574254D01*
G01D02*
X815863Y-573900D01*
G01D02*
X815891Y-573575D01*
G01D02*
X815919Y-573280D01*
G01D02*
X815946Y-573014D01*
G01D02*
X815972Y-572778D01*
G01D02*
X815998Y-572572D01*
G01D02*
X816022Y-572394D01*
G01D02*
X816045Y-572246D01*
G01D02*
X816067Y-572127D01*
G01D02*
X816085Y-572039D01*
G01D02*
X816100Y-571981D01*
G01D02*
X816101Y-571977D01*
G01X818699Y-577559D02*
X818732Y-577004D01*
G01D02*
X818764Y-576479D01*
G01D02*
X818796Y-575984D01*
G01D02*
X818826Y-575518D01*
G01D02*
X818857Y-575078D01*
G01D02*
X818887Y-574665D01*
G01D02*
X818916Y-574279D01*
G01D02*
X818945Y-573922D01*
G01D02*
X818973Y-573596D01*
G01D02*
X819001Y-573299D01*
G01D02*
X819028Y-573033D01*
G01D02*
X819054Y-572796D01*
G01D02*
X819079Y-572589D01*
G01D02*
X819104Y-572411D01*
G01D02*
X819126Y-572261D01*
G01D02*
X819148Y-572139D01*
G01D02*
X819167Y-572046D01*
G01D02*
X819183Y-571984D01*
G01D02*
X819184Y-571980D01*
G01X809449Y-577555D02*
X809480Y-577046D01*
G01D02*
X809509Y-576559D01*
G01D02*
X809539Y-576092D01*
G01D02*
X809568Y-575648D01*
G01D02*
X809596Y-575228D01*
G01D02*
X809624Y-574832D01*
G01X814465Y-577043D02*
X814427Y-577675D01*
G01D02*
X814389Y-578344D01*
G01D02*
X814349Y-579045D01*
G01D02*
X814228Y-581209D01*
G01X811330Y-577906D02*
X811294Y-578544D01*
G01D02*
X811258Y-579173D01*
G01D02*
X811159Y-580968D01*
G01X808243Y-577983D02*
X808207Y-578618D01*
G01D02*
X808170Y-579273D01*
G01D02*
X808059Y-581261D01*
G01X809180Y-582339D02*
X809217Y-581676D01*
G01D02*
X809322Y-579789D01*
G01X811159Y-580968D02*
X811096Y-582079D01*
G01X814228Y-581209D02*
X814190Y-581907D01*
G01X812409Y-579710D02*
X812446Y-579065D01*
G01D02*
X812481Y-578441D01*
G01D02*
X812515Y-577840D01*
G01X809322Y-579789D02*
X809355Y-579200D01*
G01D02*
X809387Y-578631D01*
G01D02*
X809418Y-578083D01*
G01D02*
X809449Y-577555D01*
G01X818478Y-581475D02*
X818593Y-579424D01*
G01D02*
X818629Y-578770D01*
G01D02*
X818665Y-578148D01*
G01D02*
X818699Y-577559D01*
G01X817364Y-580269D02*
X817285Y-581685D01*
G01D02*
X817247Y-582363D01*
G01X815400Y-581383D02*
X815511Y-579377D01*
G01D02*
X815547Y-578741D01*
G01D02*
X815582Y-578130D01*
G01D02*
X815616Y-577545D01*
G01X806374Y-577772D02*
X806406Y-577165D01*
G01D02*
X806438Y-576567D01*
G01D02*
X806472Y-575983D01*
G01D02*
X806506Y-575418D01*
G01D02*
X806542Y-574877D01*
G01X806228Y-580831D02*
X806255Y-580228D01*
G01D02*
X806283Y-579618D01*
G01D02*
X806313Y-579003D01*
G01D02*
X806343Y-578387D01*
G01D02*
X806374Y-577772D01*
G01X817050Y-581586D02*
X816978Y-580301D01*
G01D02*
X816942Y-579640D01*
G01D02*
X816904Y-578973D01*
G01D02*
X816867Y-578304D01*
G01D02*
X816828Y-577643D01*
G01X813946Y-581219D02*
X813863Y-579731D01*
G01D02*
X813824Y-579018D01*
G01D02*
X813785Y-578331D01*
G01D02*
X813747Y-577674D01*
G01X809556Y-578954D02*
X809623Y-580167D01*
G01D02*
X809694Y-581448D01*
G01X806478Y-579044D02*
X806541Y-580170D01*
G01D02*
X806573Y-580758D01*
G01D02*
X806641Y-581979D01*
G01X815861Y-581456D02*
X815896Y-582084D01*
G01X812778Y-581467D02*
X812817Y-582152D01*
G01X807684Y-579494D02*
X807648Y-578846D01*
G01D02*
X807612Y-578221D01*
G01D02*
X807578Y-577624D01*
G01X810766Y-579476D02*
X810729Y-578813D01*
G01D02*
X810692Y-578160D01*
G01D02*
X810655Y-577525D01*
G01X818965Y-581817D02*
X819001Y-582448D01*
G01X813989Y-581983D02*
X813946Y-581219D01*
G01X816828Y-577643D02*
X816790Y-576998D01*
G01D02*
X816752Y-576380D01*
G01D02*
X816715Y-575796D01*
G01D02*
X816679Y-575253D01*
G01D02*
X816644Y-574757D01*
G01D02*
X816610Y-574306D01*
G01D02*
X816578Y-573898D01*
G01D02*
X816546Y-573531D01*
G01D02*
X816515Y-573202D01*
G01D02*
X816486Y-572908D01*
G01D02*
X816457Y-572646D01*
G01D02*
X816428Y-572415D01*
G01D02*
X816400Y-572212D01*
G01D02*
X816372Y-572033D01*
G01D02*
X816343Y-571878D01*
G01D02*
X816313Y-571742D01*
G01D02*
X816279Y-571620D01*
G01D02*
X816236Y-571502D01*
G01D02*
X816170Y-571374D01*
G01D02*
X816050Y-571229D01*
G01D02*
X815839Y-571102D01*
G01D02*
X815629Y-571065D01*
G01X813747Y-577674D02*
X813710Y-577049D01*
G01D02*
X813674Y-576457D01*
G01D02*
X813638Y-575901D01*
G01D02*
X813604Y-575381D01*
G01D02*
X813570Y-574897D01*
G01D02*
X813537Y-574450D01*
G01D02*
X813506Y-574041D01*
G01D02*
X813475Y-573668D01*
G01D02*
X813444Y-573332D01*
G01D02*
X813415Y-573030D01*
G01D02*
X813386Y-572759D01*
G01D02*
X813358Y-572519D01*
G01D02*
X813330Y-572306D01*
G01D02*
X813302Y-572118D01*
G01D02*
X813274Y-571951D01*
G01D02*
X813244Y-571805D01*
G01D02*
X813212Y-571677D01*
G01D02*
X813175Y-571559D01*
G01D02*
X813123Y-571439D01*
G01D02*
X813035Y-571302D01*
G01D02*
X812871Y-571158D01*
G01D02*
X812619Y-571069D01*
G01D02*
X812545Y-571065D01*
G01X812538Y-577213D02*
X812565Y-577665D01*
G01D02*
X812598Y-578247D01*
G01D02*
X812633Y-578853D01*
G01D02*
X812668Y-579481D01*
G01X807578Y-577624D02*
X807544Y-577059D01*
G01D02*
X807512Y-576525D01*
G01D02*
X807480Y-576022D01*
G01D02*
X807449Y-575549D01*
G01D02*
X807419Y-575104D01*
G01D02*
X807391Y-574713D01*
G01X818695Y-577049D02*
X818727Y-577575D01*
G01D02*
X818759Y-578128D01*
G01D02*
X818792Y-578705D01*
G01D02*
X818826Y-579304D01*
G01X810655Y-577525D02*
X810619Y-576919D01*
G01D02*
X810583Y-576348D01*
G01D02*
X810550Y-575816D01*
G01D02*
X810517Y-575320D01*
G01D02*
X810485Y-574861D01*
G01X806359Y-576996D02*
X806388Y-577481D01*
G01D02*
X806417Y-577985D01*
G01D02*
X806447Y-578506D01*
G01D02*
X806478Y-579044D01*
G01X815600Y-576865D02*
X815631Y-577365D01*
G01D02*
X815661Y-577889D01*
G01D02*
X815693Y-578437D01*
G01D02*
X815725Y-579008D01*
G01X809429Y-576779D02*
X809459Y-577289D01*
G01D02*
X809491Y-577821D01*
G01D02*
X809523Y-578377D01*
G01D02*
X809556Y-578954D01*
G01X809283Y-574597D02*
X809311Y-574984D01*
G01D02*
X809340Y-575396D01*
G01D02*
X809369Y-575832D01*
G01D02*
X809398Y-576293D01*
G01D02*
X809429Y-576779D01*
G01X810485Y-574861D02*
X810453Y-574435D01*
G01D02*
X810423Y-574043D01*
G01D02*
X810393Y-573682D01*
G01D02*
X810363Y-573352D01*
G01D02*
X810334Y-573052D01*
G01D02*
X810306Y-572782D01*
G01D02*
X810278Y-572540D01*
G01D02*
X810250Y-572325D01*
G01D02*
X810222Y-572135D01*
G01X806220Y-574877D02*
X806247Y-575257D01*
G01D02*
X806274Y-575659D01*
G01D02*
X806302Y-576083D01*
G01D02*
X806330Y-576529D01*
G01D02*
X806359Y-576996D01*
G01X807360Y-574297D02*
X807331Y-573933D01*
G01D02*
X807302Y-573595D01*
G01D02*
X807274Y-573284D01*
G01D02*
X807246Y-573000D01*
G01D02*
X807219Y-572743D01*
G01D02*
X807191Y-572511D01*
G01D02*
X807164Y-572305D01*
G01D02*
X807137Y-572122D01*
G01X823465Y-571404D02*
X823372Y-571264D01*
G01D02*
X823210Y-571136D01*
G01D02*
X822993Y-571067D01*
G01D02*
X822926Y-571063D01*
G01X806855Y-571969D02*
X806858Y-571959D01*
G01D02*
X806848Y-571980D01*
G01D02*
X806798Y-572055D01*
G01D02*
X806664Y-572167D01*
G01D02*
X806443Y-572241D01*
G01D02*
X806380Y-572245D01*
G01X809933Y-571984D02*
X809941Y-571960D01*
G01D02*
X809934Y-571975D01*
G01D02*
X809891Y-572043D01*
G01D02*
X809769Y-572154D01*
G01D02*
X809544Y-572239D01*
G01D02*
X809463Y-572245D01*
G01X809970Y-571324D02*
X809815Y-571175D01*
G01D02*
X809555Y-571072D01*
G01D02*
X809462Y-571065D01*
G01X815629Y-572246D02*
X815410Y-572200D01*
G01D02*
X815243Y-572090D01*
G01D02*
X815171Y-571999D01*
G01D02*
X815151Y-571962D01*
G01X818712Y-572246D02*
X818493Y-572200D01*
G01D02*
X818320Y-572084D01*
G01D02*
X818251Y-571994D01*
G01D02*
X818234Y-571961D01*
G01X812545Y-572246D02*
X812453Y-572238D01*
G01D02*
X812238Y-572153D01*
G01D02*
X812120Y-572046D01*
G01D02*
X812074Y-571976D01*
G01D02*
X812067Y-571960D01*
G01X821637Y-572245D02*
X821557Y-572239D01*
G01D02*
X821343Y-572164D01*
G01D02*
X821204Y-572048D01*
G01D02*
X821137Y-571948D01*
G01D02*
X821114Y-571895D01*
G01D02*
X821110Y-571883D01*
G01X822926Y-572244D02*
X822862Y-572241D01*
G01D02*
X822651Y-572175D01*
G01D02*
X822496Y-572056D01*
G01D02*
X822410Y-571932D01*
G01D02*
X822377Y-571853D01*
G01D02*
X822368Y-571820D01*
G01D02*
X822367Y-571817D01*
G01X806380Y-572245D02*
X806316Y-572241D01*
G01X809463Y-572245D02*
X809404Y-572242D01*
G01D02*
X809174Y-572165D01*
G01D02*
X809040Y-572050D01*
G01D02*
X808991Y-571975D01*
G01D02*
X808983Y-571959D01*
G01X818712Y-571065D02*
X818630Y-571070D01*
G01D02*
X818373Y-571166D01*
G01D02*
X818207Y-571320D01*
G01D02*
X818122Y-571463D01*
G01D02*
X818072Y-571590D01*
G01D02*
X818034Y-571720D01*
G01D02*
X818000Y-571866D01*
G01D02*
X817969Y-572033D01*
G01D02*
X817939Y-572224D01*
G01D02*
X817909Y-572443D01*
G01D02*
X817879Y-572693D01*
G01D02*
X817848Y-572976D01*
G01D02*
X817817Y-573296D01*
G01D02*
X817784Y-573656D01*
G01D02*
X817750Y-574058D01*
G01D02*
X817716Y-574505D01*
G01D02*
X817680Y-574998D01*
G01D02*
X817643Y-575539D01*
G01D02*
X817605Y-576127D01*
G01D02*
X817565Y-576756D01*
G01X822926Y-571063D02*
X822844Y-571069D01*
G01D02*
X822632Y-571142D01*
G01D02*
X822475Y-571270D01*
G01D02*
X822385Y-571410D01*
G01D02*
X822346Y-571513D01*
G01D02*
X822328Y-571585D01*
G01D02*
X822317Y-571647D01*
G01D02*
X822308Y-571712D01*
G01D02*
X822300Y-571785D01*
G01D02*
X822292Y-571869D01*
G01D02*
X822284Y-571967D01*
G01D02*
X822276Y-572081D01*
G01D02*
X822267Y-572214D01*
G01D02*
X822259Y-572366D01*
G01D02*
X822250Y-572538D01*
G01D02*
X822241Y-572732D01*
G01D02*
X822232Y-572948D01*
G01D02*
X822223Y-573185D01*
G01D02*
X822214Y-573445D01*
G01D02*
X822204Y-573727D01*
G01D02*
X822194Y-574030D01*
G01D02*
X822185Y-574353D01*
G01D02*
X822175Y-574695D01*
G01D02*
X822165Y-575054D01*
G01D02*
X822155Y-575429D01*
G01D02*
X822145Y-575818D01*
G01D02*
X822135Y-576217D01*
G01D02*
X822126Y-576626D01*
G01D02*
X822087Y-578306D01*
G01X821637Y-571064D02*
X821551Y-571070D01*
G01D02*
X821325Y-571152D01*
G01D02*
X821172Y-571283D01*
G01D02*
X821091Y-571406D01*
G01D02*
X821049Y-571502D01*
G01D02*
X821023Y-571583D01*
G01D02*
X821003Y-571663D01*
G01D02*
X820986Y-571750D01*
G01D02*
X820970Y-571844D01*
G01D02*
X820955Y-571950D01*
G01D02*
X820939Y-572068D01*
G01D02*
X820924Y-572200D01*
G01D02*
X820908Y-572348D01*
G01D02*
X820893Y-572513D01*
G01D02*
X820876Y-572695D01*
G01D02*
X820859Y-572896D01*
G01D02*
X820842Y-573117D01*
G01D02*
X820824Y-573358D01*
G01D02*
X820806Y-573620D01*
G01D02*
X820787Y-573905D01*
G01D02*
X820767Y-574211D01*
G01D02*
X820747Y-574540D01*
G01D02*
X820726Y-574892D01*
G01D02*
X820704Y-575267D01*
G01D02*
X820682Y-575665D01*
G01D02*
X820659Y-576085D01*
G01D02*
X820635Y-576526D01*
G01D02*
X820611Y-576990D01*
G01X806380Y-571064D02*
X806288Y-571071D01*
G01X815629Y-571065D02*
X815530Y-571073D01*
G01D02*
X815278Y-571174D01*
G01D02*
X815125Y-571319D01*
G01D02*
X815044Y-571452D01*
G01D02*
X814996Y-571568D01*
G01D02*
X814960Y-571684D01*
G01D02*
X814929Y-571810D01*
G01D02*
X814900Y-571952D01*
G01D02*
X814872Y-572113D01*
G01D02*
X814845Y-572297D01*
G01D02*
X814817Y-572507D01*
G01D02*
X814789Y-572745D01*
G01D02*
X814761Y-573014D01*
G01D02*
X814731Y-573317D01*
G01D02*
X814700Y-573654D01*
G01D02*
X814669Y-574028D01*
G01D02*
X814637Y-574438D01*
G01D02*
X814604Y-574885D01*
G01D02*
X814571Y-575369D01*
G01D02*
X814536Y-575889D01*
G01D02*
X814501Y-576447D01*
G01D02*
X814465Y-577043D01*
G01X809463Y-571065D02*
X809360Y-571073D01*
G01D02*
X809104Y-571179D01*
G01D02*
X808952Y-571328D01*
G01D02*
X808872Y-571463D01*
G01D02*
X808824Y-571583D01*
G01D02*
X808788Y-571703D01*
G01D02*
X808757Y-571835D01*
G01D02*
X808728Y-571983D01*
G01X812546Y-571065D02*
X812439Y-571074D01*
G01D02*
X812183Y-571181D01*
G01D02*
X812034Y-571330D01*
G01D02*
X811955Y-571464D01*
G01D02*
X811908Y-571581D01*
G01D02*
X811872Y-571699D01*
G01D02*
X811841Y-571829D01*
G01D02*
X811812Y-571976D01*
G01D02*
X811784Y-572143D01*
G01D02*
X811757Y-572334D01*
G01D02*
X811729Y-572551D01*
G01D02*
X811700Y-572797D01*
G01D02*
X811671Y-573073D01*
G01D02*
X811641Y-573381D01*
G01D02*
X811611Y-573724D01*
G01D02*
X811580Y-574104D01*
G01D02*
X811547Y-574526D01*
G01D02*
X811513Y-574992D01*
G01D02*
X811478Y-575506D01*
G01D02*
X811442Y-576062D01*
G01D02*
X811405Y-576654D01*
G01D02*
X811371Y-577213D01*
G01X812265Y-582315D02*
X812300Y-581677D01*
G01D02*
X812409Y-579710D01*
G01X815362Y-582067D02*
X815400Y-581383D01*
G01X818441Y-582146D02*
X818478Y-581475D01*
G01X868813Y-777373D02*
Y-796310D01*
G01X922925Y-586337D02*
X914264D01*
X915996Y-587636D01*
G01X922925D02*
Y-585038D01*
G01X923214Y-577676D02*
X923069Y-577893D01*
X922781D01*
X922636Y-577676D01*
X922781Y-577459D01*
X923069D01*
X923214Y-577676D01*
G01X919316Y-571072D02*
X918306Y-570314D01*
X917728Y-569665D01*
X917440Y-568798D01*
X917728Y-568041D01*
X918306Y-567499D01*
X919172Y-567066D01*
X920182Y-566958D01*
X921049Y-567066D01*
X921915Y-567499D01*
X922636Y-568149D01*
X922925Y-568907D01*
X922636Y-569773D01*
X921770Y-570531D01*
X920471Y-570964D01*
X919028Y-571072D01*
X917151Y-570856D01*
X916140Y-570531D01*
X915130Y-569989D01*
X914408Y-569232D01*
X914264Y-568474D01*
X914553Y-567716D01*
X915274Y-567174D01*
G01X914264Y-560354D02*
X914553Y-561220D01*
X915274Y-561870D01*
X916140Y-562303D01*
X917295Y-562628D01*
X918595Y-562736D01*
X919894Y-562628D01*
X921049Y-562303D01*
X921915Y-561870D01*
X922636Y-561220D01*
X922925Y-560354D01*
X922636Y-559488D01*
X921915Y-558838D01*
X921049Y-558405D01*
X919894Y-558080D01*
X918595Y-557972D01*
X917295Y-558080D01*
X916140Y-558405D01*
X915274Y-558838D01*
X914553Y-559488D01*
X914264Y-560354D01*
G01X868813Y1400383D02*
Y1381446D01*
G01X977005Y-786023D02*
X978370Y-784203D01*
X979540Y-783163D01*
X981100Y-782643D01*
X982465Y-783163D01*
X983440Y-784203D01*
X984220Y-785763D01*
X984415Y-787583D01*
X984220Y-789143D01*
X983440Y-790703D01*
X982270Y-792003D01*
X980905Y-792523D01*
X979345Y-792003D01*
X977980Y-790443D01*
X977200Y-788103D01*
X977005Y-785503D01*
X977395Y-782123D01*
X977980Y-780303D01*
X978955Y-778483D01*
X980320Y-777183D01*
X981685Y-776923D01*
X983050Y-777443D01*
X984025Y-778743D01*
G01X925090Y-599213D02*
Y-558404D01*
G01D02*
Y-602362D01*
G01Y-605512D02*
Y-625197D01*
G01D02*
Y-602362D01*
G01X953111Y-7874D02*
G03Y0I0J3937D01*
G01Y472441D02*
G03Y480315I0J3937D01*
G01Y952756D02*
G03Y960630I0J3937D01*
G01X977005Y1391733D02*
X978370Y1393553D01*
X979540Y1394593D01*
X981100Y1395113D01*
X982465Y1394593D01*
X983440Y1393553D01*
X984220Y1391993D01*
X984415Y1390173D01*
X984220Y1388613D01*
X983440Y1387053D01*
X982270Y1385753D01*
X980905Y1385233D01*
X979345Y1385753D01*
X977980Y1387313D01*
X977200Y1389653D01*
X977005Y1392253D01*
X977395Y1395633D01*
X977980Y1397453D01*
X978955Y1399273D01*
X980320Y1400573D01*
X981685Y1400833D01*
X983050Y1400313D01*
X984025Y1399013D01*
G01X983820Y0D02*
G03Y-7874I0J-3937D01*
G01X1180670D02*
X983820D01*
G01X1000886Y233575D02*
Y253260D01*
G01X1006545Y233575D02*
X995227D01*
G01X983820Y480315D02*
G03Y472441I0J-3937D01*
G01X1005473Y678332D02*
Y698017D01*
G01X1011132Y678332D02*
X999814D01*
G01X983820Y960630D02*
G03Y952756I0J-3937D01*
G01X1180670Y960630D02*
X983820D01*
G01X1088482Y-777373D02*
Y-796310D01*
G01Y1400383D02*
Y1381446D01*
G01X1199990Y-792523D02*
X1200380Y-789143D01*
X1200965Y-786283D01*
X1201745Y-783683D01*
X1202720Y-780823D01*
X1204280Y-776923D01*
X1196480D01*
G01X1180670Y-7874D02*
G03Y0I0J3937D01*
G01Y472441D02*
G03Y480315I0J3937D01*
G01Y952756D02*
G03Y960630I0J3937D01*
G01X1199990Y1385233D02*
X1200380Y1388613D01*
X1200965Y1391473D01*
X1201745Y1394073D01*
X1202720Y1396933D01*
X1204280Y1400833D01*
X1196480D01*
G01X1211380Y-7874D02*
X1284723D01*
G01X1211380Y0D02*
G03Y-7874I0J-3937D01*
G01X1265491Y57087D02*
G03X1251514Y57086I-6989J0D01*
G03X1265491Y57087I6988J1D01*
G01X1259605Y226378D02*
Y246063D01*
G01X1263542Y250000D02*
G03X1259605Y246063I0J-3937D01*
G01Y226378D02*
G03X1263542Y222441I3937J0D01*
G01X1265491Y411417D02*
G03X1251514Y411418I-6989J0D01*
G03X1265491Y411417I6988J-1D01*
G01X1211380Y480315D02*
G03Y472441I0J-3937D01*
G01X1265491Y537402D02*
G03X1251514Y537401I-6989J0D01*
G03X1265491Y537402I6988J1D01*
G01X1259605Y706693D02*
Y726378D01*
G01X1263542Y730315D02*
G03X1259605Y726378I0J-3937D01*
G01Y706693D02*
G03X1263542Y702756I3937J0D01*
G01X1265491Y891732D02*
G03X1251514Y891733I-6989J0D01*
G03X1265491Y891732I6988J-1D01*
G01X1211380Y960630D02*
G03Y952756I0J-3937D01*
G01Y960630D02*
X1284723D01*
G01X1308151Y-777373D02*
Y-796310D01*
G01X1317968Y-19685D02*
G03X1331968Y-5685I0J14000D01*
G01X1288660Y102559D02*
Y3937D01*
G01Y102559D02*
Y3937D01*
G01X1284723Y0D02*
G03X1288660Y3937I0J3937D01*
G01X1284723Y0D02*
G03X1288660Y3937I0J3937D01*
G01X1284723Y-7874D02*
G03X1296534Y3937I0J11811D01*
G01D02*
Y45847D01*
G01D02*
G03X1288660I-3937J0D01*
G01X1316572Y15749D02*
G03X1307990I-4291J0D01*
G01D02*
G03X1316572I4291J0D01*
G01X1292597Y106496D02*
G03X1288660Y102559I0J-3937D01*
G01X1292597Y106496D02*
G03X1288660Y102559I0J-3937D01*
G01X1331968Y98622D02*
X1296534D01*
G01D02*
Y71044D01*
G01X1288660D02*
G03X1296534I3937J0D01*
G01X1292597Y106496D02*
X1326061D01*
G01X1292597D02*
X1326061D01*
G01X1301258Y180394D02*
X1326061D01*
G01D02*
X1290038D01*
G01X1301258D02*
X1290038D01*
G01X1326061Y177638D02*
X1290038D01*
G01X1326061D02*
X1290038D01*
G01Y180394D02*
G03Y177638I0J-1378D01*
G01Y180394D02*
G03Y177638I0J-1378D01*
G01X1271416Y246063D02*
Y226378D01*
G01X1263542Y250000D02*
X1267479D01*
G01Y222441D02*
X1263542D01*
G01X1271416Y246063D02*
G03X1267479Y250000I-3937J0D01*
G01Y222441D02*
G03X1271416Y226378I0J3937D01*
G01X1288660Y468504D02*
Y365472D01*
G01Y468504D02*
Y365472D01*
G01X1326061Y361535D02*
X1292597D01*
G01X1326061D02*
X1292597D01*
G01X1288660Y365472D02*
G03X1292597Y361535I3937J0D01*
G01X1288660Y365472D02*
G03X1292597Y361535I3937J0D01*
G01X1331968Y369409D02*
X1296534D01*
G01D02*
Y396985D01*
G01D02*
G03X1288660I-3937J0D01*
G01X1296534Y526162D02*
Y422182D01*
G01X1288660D02*
G03X1296534I3937J0D01*
G01X1288660Y582874D02*
Y484252D01*
G01Y582874D02*
Y484252D01*
G01X1284723Y480315D02*
G03X1288660Y484252I0J3937D01*
G01X1284723Y480315D02*
G03X1288660Y484252I0J3937D01*
G01Y468504D02*
G03X1284723Y472441I-3937J0D01*
G01X1288660Y468504D02*
G03X1284723Y472441I-3937J0D01*
G01X1296534Y578937D02*
Y551359D01*
G01X1288660D02*
G03X1296534I3937J0D01*
G01Y526162D02*
G03X1288660I-3937J0D01*
G01X1292597Y586811D02*
X1326061D01*
G01X1292597D02*
X1326061D01*
G01X1292597D02*
G03X1288660Y582874I0J-3937D01*
G01X1292597Y586811D02*
G03X1288660Y582874I0J-3937D01*
G01X1331968Y578937D02*
X1296534D01*
G01X1301258Y660709D02*
X1326061D01*
G01D02*
X1290038D01*
G01X1301258D02*
X1290038D01*
G01X1326061Y657953D02*
X1290038D01*
G01X1326061D02*
X1290038D01*
G01Y660709D02*
G03Y657953I0J-1378D01*
G01Y660709D02*
G03Y657953I0J-1378D01*
G01X1271416Y726378D02*
Y706693D01*
G01X1263542Y730315D02*
X1267479D01*
G01Y702756D02*
X1263542D01*
G01X1271416Y726378D02*
G03X1267479Y730315I-3937J0D01*
G01Y702756D02*
G03X1271416Y706693I0J3937D01*
G01X1326061Y841850D02*
X1292597D01*
G01X1326061D02*
X1292597D01*
G01X1288660Y845787D02*
G03X1292597Y841850I3937J0D01*
G01X1288660Y845787D02*
G03X1292597Y841850I3937J0D01*
G01X1288660Y948819D02*
Y845787D01*
G01Y948819D02*
Y845787D01*
G01X1296534Y849724D02*
Y877300D01*
G01Y877296D02*
G03X1288660I-3937J0D01*
G01X1296534Y948819D02*
Y902497D01*
G01X1288660D02*
G03X1296534I3937J0D01*
G01X1331968Y849724D02*
X1296534D01*
G01X1316572Y889328D02*
G03X1307990I-4291J0D01*
G01D02*
G03X1316572I4291J0D01*
G01X1288660Y948819D02*
G03X1284723Y952756I-3937J0D01*
G01X1288660Y948819D02*
G03X1284723Y952756I-3937J0D01*
G01X1296534Y948819D02*
G03X1284723Y960630I-11811J0D01*
G01X1331968Y958441D02*
G03X1317968Y972441I-14000J0D01*
G01X1308151Y1400383D02*
Y1381446D01*
G01X1331968Y-5685D02*
Y98622D01*
G01X1331967Y112402D02*
Y171732D01*
G01X1326061Y106496D02*
X1329998Y110433D01*
G01X1326061Y106496D02*
X1331967Y112402D01*
G01Y186299D02*
Y355630D01*
G01X1326061Y180394D02*
X1329998Y184331D01*
G01X1326061Y180394D02*
X1331967Y186299D01*
G01Y171732D02*
X1326061Y177638D01*
G01X1329998Y173701D02*
X1326061Y177638D01*
G01X1331967Y355630D02*
X1326061Y361535D01*
G01X1329998Y357598D02*
X1326061Y361535D01*
G01X1331968Y578937D02*
Y369409D01*
G01X1331967Y592717D02*
Y652047D01*
G01X1326061Y586811D02*
X1329998Y590748D01*
G01X1326061Y586811D02*
X1331967Y592717D01*
G01Y666614D02*
Y835945D01*
G01X1326061Y660709D02*
X1329998Y664646D01*
G01X1326061Y660709D02*
X1331967Y666614D01*
G01Y652047D02*
X1326061Y657953D01*
G01X1329998Y654016D02*
X1326061Y657953D01*
G01X1331967Y835945D02*
X1326061Y841850D01*
G01X1329998Y837913D02*
X1326061Y841850D01*
G01X1331968Y958441D02*
Y849724D01*
G01Y1000315D02*
Y966315D01*
G01X1332961Y1001181D02*
X1333971Y1001831D01*
X1334549Y1002697D01*
X1334693Y1003671D01*
X1334549Y1004537D01*
X1333827Y1005404D01*
X1332961Y1005945D01*
X1332095Y1006053D01*
X1331084Y1005837D01*
X1330363Y1005079D01*
X1330074Y1004321D01*
Y1003346D01*
G01Y1004321D02*
X1329641Y1004970D01*
X1328919Y1005512D01*
X1328053Y1005728D01*
X1327187Y1005512D01*
X1326465Y1004970D01*
X1326032Y1003996D01*
X1326176Y1003022D01*
X1326754Y1002047D01*
G01X1334693Y1013523D02*
X1326032D01*
X1332239Y1009517D01*
Y1014931D01*
G01X1333683Y1019044D02*
X1334404Y1019802D01*
X1334693Y1020668D01*
X1334404Y1021535D01*
X1333538Y1022292D01*
X1332239Y1022834D01*
X1330940Y1023050D01*
X1329352D01*
X1328053Y1022834D01*
X1326898Y1022292D01*
X1326321Y1021643D01*
X1326032Y1020885D01*
X1326321Y1020019D01*
X1326898Y1019369D01*
X1327764Y1018936D01*
X1328919Y1018720D01*
X1329929Y1018936D01*
X1330940Y1019478D01*
X1331517Y1020127D01*
X1331662Y1020885D01*
X1331373Y1021751D01*
X1330651Y1022401D01*
X1329352Y1023050D01*
G01X1334982Y1029546D02*
X1334837Y1029329D01*
X1334549D01*
X1334404Y1029546D01*
X1334549Y1029763D01*
X1334837D01*
X1334982Y1029546D01*
G01X1332961Y1035825D02*
X1333971Y1036475D01*
X1334549Y1037341D01*
X1334693Y1038315D01*
X1334549Y1039181D01*
X1333827Y1040048D01*
X1332961Y1040589D01*
X1332095Y1040697D01*
X1331084Y1040481D01*
X1330363Y1039723D01*
X1330074Y1038965D01*
Y1037990D01*
G01Y1038965D02*
X1329641Y1039614D01*
X1328919Y1040156D01*
X1328053Y1040372D01*
X1327187Y1040156D01*
X1326465Y1039614D01*
X1326032Y1038640D01*
X1326176Y1037666D01*
X1326754Y1036691D01*
G01X1327475Y1044811D02*
X1326610Y1045461D01*
X1326176Y1046218D01*
X1326032Y1047085D01*
X1326321Y1048167D01*
X1327042Y1048925D01*
X1327908Y1049142D01*
X1328775Y1049033D01*
X1329496Y1048600D01*
X1330940Y1046435D01*
X1331950Y1045461D01*
X1333394Y1044811D01*
X1334693Y1044594D01*
Y1049142D01*
G01X1420049Y-792523D02*
X1421414Y-792263D01*
X1422974Y-791483D01*
X1423949Y-790183D01*
X1424339Y-788363D01*
X1423949Y-786543D01*
X1422779Y-784983D01*
X1421024Y-784203D01*
X1419074D01*
X1417904Y-783683D01*
X1416929Y-782383D01*
X1416539Y-780563D01*
X1417124Y-778743D01*
X1418489Y-777443D01*
X1420049Y-776923D01*
X1421609Y-777443D01*
X1422974Y-778743D01*
X1423559Y-780563D01*
X1423169Y-782383D01*
X1422194Y-783683D01*
X1421024Y-784203D01*
X1419074D01*
X1417319Y-784983D01*
X1416149Y-786543D01*
X1415759Y-788363D01*
X1416149Y-790183D01*
X1417124Y-791483D01*
X1418684Y-792263D01*
X1420049Y-792523D01*
G01Y1385233D02*
X1421414Y1385493D01*
X1422974Y1386273D01*
X1423949Y1387573D01*
X1424339Y1389393D01*
X1423949Y1391213D01*
X1422779Y1392773D01*
X1421024Y1393553D01*
X1419074D01*
X1417904Y1394073D01*
X1416929Y1395373D01*
X1416539Y1397193D01*
X1417124Y1399013D01*
X1418489Y1400313D01*
X1420049Y1400833D01*
X1421609Y1400313D01*
X1422974Y1399013D01*
X1423559Y1397193D01*
X1423169Y1395373D01*
X1422194Y1394073D01*
X1421024Y1393553D01*
X1419074D01*
X1417319Y1392773D01*
X1416149Y1391213D01*
X1415759Y1389393D01*
X1416149Y1387573D01*
X1417124Y1386273D01*
X1418684Y1385493D01*
X1420049Y1385233D01*
G01X1527821Y-777373D02*
Y-796310D01*
G01Y1400383D02*
Y1381446D01*
G01X1636404Y-790703D02*
X1637769Y-792003D01*
X1639329Y-792523D01*
X1640889Y-792003D01*
X1642254Y-790443D01*
X1643229Y-788103D01*
X1643619Y-785763D01*
Y-782903D01*
X1643229Y-780563D01*
X1642254Y-778483D01*
X1641084Y-777443D01*
X1639719Y-776923D01*
X1638159Y-777443D01*
X1636989Y-778483D01*
X1636209Y-780043D01*
X1635819Y-782123D01*
X1636209Y-783943D01*
X1637184Y-785763D01*
X1638354Y-786803D01*
X1639719Y-787063D01*
X1641279Y-786543D01*
X1642449Y-785243D01*
X1643619Y-782903D01*
G01X1636404Y1387053D02*
X1637769Y1385753D01*
X1639329Y1385233D01*
X1640889Y1385753D01*
X1642254Y1387313D01*
X1643229Y1389653D01*
X1643619Y1391993D01*
Y1394853D01*
X1643229Y1397193D01*
X1642254Y1399273D01*
X1641084Y1400313D01*
X1639719Y1400833D01*
X1638159Y1400313D01*
X1636989Y1399273D01*
X1636209Y1397713D01*
X1635819Y1395633D01*
X1636209Y1393813D01*
X1637184Y1391993D01*
X1638354Y1390953D01*
X1639719Y1390693D01*
X1641279Y1391213D01*
X1642449Y1392513D01*
X1643619Y1394853D01*
G01X1747491Y-777373D02*
Y-796310D01*
G01X1768160Y-273664D02*
X1767294Y-273953D01*
X1766644Y-274674D01*
X1766211Y-275540D01*
X1765886Y-276695D01*
X1765778Y-277995D01*
X1765886Y-279294D01*
X1766211Y-280449D01*
X1766644Y-281315D01*
X1767294Y-282036D01*
X1768160Y-282325D01*
X1769026Y-282036D01*
X1769676Y-281315D01*
X1770109Y-280449D01*
X1770434Y-279294D01*
X1770542Y-277995D01*
X1770434Y-276695D01*
X1770109Y-275540D01*
X1769676Y-274674D01*
X1769026Y-273953D01*
X1768160Y-273664D01*
G01X1776821Y-282614D02*
X1776604Y-282469D01*
Y-282181D01*
X1776821Y-282036D01*
X1777038Y-282181D01*
Y-282469D01*
X1776821Y-282614D01*
G01X1785482Y-273664D02*
X1784616Y-273953D01*
X1783966Y-274674D01*
X1783533Y-275540D01*
X1783208Y-276695D01*
X1783100Y-277995D01*
X1783208Y-279294D01*
X1783533Y-280449D01*
X1783966Y-281315D01*
X1784616Y-282036D01*
X1785482Y-282325D01*
X1786348Y-282036D01*
X1786998Y-281315D01*
X1787431Y-280449D01*
X1787756Y-279294D01*
X1787864Y-277995D01*
X1787756Y-276695D01*
X1787431Y-275540D01*
X1786998Y-274674D01*
X1786348Y-273953D01*
X1785482Y-273664D01*
G01X1794143D02*
X1793277Y-273953D01*
X1792627Y-274674D01*
X1792194Y-275540D01*
X1791869Y-276695D01*
X1791761Y-277995D01*
X1791869Y-279294D01*
X1792194Y-280449D01*
X1792627Y-281315D01*
X1793277Y-282036D01*
X1794143Y-282325D01*
X1795009Y-282036D01*
X1795659Y-281315D01*
X1796092Y-280449D01*
X1796417Y-279294D01*
X1796525Y-277995D01*
X1796417Y-276695D01*
X1796092Y-275540D01*
X1795659Y-274674D01*
X1795009Y-273953D01*
X1794143Y-273664D01*
G01X1848126Y190972D02*
X1741302D01*
G01X1751588Y200355D02*
X1752238Y201220D01*
X1752995Y201654D01*
X1753862Y201798D01*
X1754944Y201509D01*
X1755702Y200788D01*
X1755919Y199922D01*
X1755810Y199055D01*
X1755377Y198334D01*
X1753212Y196890D01*
X1752238Y195880D01*
X1751588Y194436D01*
X1751371Y193137D01*
X1755919D01*
G01X1760032D02*
X1764580Y201798D01*
G01X1760032D02*
X1764580Y193137D01*
G01X1772013D02*
Y198911D01*
G01Y197467D02*
X1772447Y198189D01*
X1773096Y198767D01*
X1773962Y198911D01*
X1774720Y198767D01*
X1775370Y198189D01*
X1775695Y197179D01*
Y193137D01*
G01X1776670Y194869D02*
X1777320Y193859D01*
X1778186Y193281D01*
X1779160Y193137D01*
X1780026Y193281D01*
X1780893Y194003D01*
X1781434Y194869D01*
X1781542Y195735D01*
X1781326Y196746D01*
X1780568Y197467D01*
X1779810Y197756D01*
X1778835D01*
G01X1779810D02*
X1780459Y198189D01*
X1781001Y198911D01*
X1781217Y199777D01*
X1781001Y200643D01*
X1780459Y201365D01*
X1779485Y201798D01*
X1778511Y201654D01*
X1777536Y201076D01*
G01X1787713Y192848D02*
X1787496Y192993D01*
Y193281D01*
X1787713Y193426D01*
X1787930Y193281D01*
Y192993D01*
X1787713Y192848D01*
G01X1793992Y194436D02*
X1794642Y193714D01*
X1795400Y193281D01*
X1796374Y193137D01*
X1797348Y193426D01*
X1798106Y194003D01*
X1798648Y195013D01*
X1798756Y196168D01*
X1798539Y197323D01*
X1797998Y198045D01*
X1797240Y198622D01*
X1796482Y198767D01*
X1795724Y198622D01*
X1794750Y198045D01*
X1795075Y201798D01*
X1797998D01*
G01X1802653Y194436D02*
X1803303Y193714D01*
X1804061Y193281D01*
X1805035Y193137D01*
X1806009Y193426D01*
X1806767Y194003D01*
X1807309Y195013D01*
X1807417Y196168D01*
X1807200Y197323D01*
X1806659Y198045D01*
X1805901Y198622D01*
X1805143Y198767D01*
X1804385Y198622D01*
X1803411Y198045D01*
X1803736Y201798D01*
X1806659D01*
G01X1775037Y966336D02*
Y974997D01*
X1773738Y973265D01*
G01Y966336D02*
X1776336D01*
G01X1781641Y973554D02*
X1782291Y974419D01*
X1783048Y974853D01*
X1783915Y974997D01*
X1784997Y974708D01*
X1785755Y973987D01*
X1785972Y973121D01*
X1785863Y972254D01*
X1785430Y971533D01*
X1783265Y970089D01*
X1782291Y969079D01*
X1781641Y967635D01*
X1781424Y966336D01*
X1785972D01*
G01X1792359Y974997D02*
X1791493Y974708D01*
X1790843Y973987D01*
X1790410Y973121D01*
X1790085Y971966D01*
X1789977Y970666D01*
X1790085Y969367D01*
X1790410Y968212D01*
X1790843Y967346D01*
X1791493Y966625D01*
X1792359Y966336D01*
X1793225Y966625D01*
X1793875Y967346D01*
X1794308Y968212D01*
X1794633Y969367D01*
X1794741Y970666D01*
X1794633Y971966D01*
X1794308Y973121D01*
X1793875Y973987D01*
X1793225Y974708D01*
X1792359Y974997D01*
G01X1801020Y966047D02*
X1800803Y966192D01*
Y966480D01*
X1801020Y966625D01*
X1801237Y966480D01*
Y966192D01*
X1801020Y966047D01*
G01X1809681Y974997D02*
X1808815Y974708D01*
X1808165Y973987D01*
X1807732Y973121D01*
X1807407Y971966D01*
X1807299Y970666D01*
X1807407Y969367D01*
X1807732Y968212D01*
X1808165Y967346D01*
X1808815Y966625D01*
X1809681Y966336D01*
X1810547Y966625D01*
X1811197Y967346D01*
X1811630Y968212D01*
X1811955Y969367D01*
X1812063Y970666D01*
X1811955Y971966D01*
X1811630Y973121D01*
X1811197Y973987D01*
X1810547Y974708D01*
X1809681Y974997D01*
G01X1818342D02*
X1817476Y974708D01*
X1816826Y973987D01*
X1816393Y973121D01*
X1816068Y971966D01*
X1815960Y970666D01*
X1816068Y969367D01*
X1816393Y968212D01*
X1816826Y967346D01*
X1817476Y966625D01*
X1818342Y966336D01*
X1819208Y966625D01*
X1819858Y967346D01*
X1820291Y968212D01*
X1820616Y969367D01*
X1820724Y970666D01*
X1820616Y971966D01*
X1820291Y973121D01*
X1819858Y973987D01*
X1819208Y974708D01*
X1818342Y974997D01*
G01X1747491Y1400383D02*
Y1381446D01*
G01X1811321Y-777373D02*
X2201084D01*
G01X1899547Y-284491D02*
X1801721D01*
G01X1816730Y193137D02*
Y201798D01*
X1819328D01*
X1820194Y201365D01*
X1820844Y200355D01*
X1821060Y199200D01*
X1820844Y198045D01*
X1820302Y197179D01*
X1819328Y196746D01*
X1816730D01*
G01X1827556Y201798D02*
Y193137D01*
G01X1825066Y201798D02*
X1830046D01*
G01X1833943Y193137D02*
Y201798D01*
G01X1838491D02*
Y193137D01*
G01Y197467D02*
X1833943D01*
G01X1908166Y491730D02*
X1825920D01*
G01X1792359Y502556D02*
X1791493Y502267D01*
X1790843Y501546D01*
X1790410Y500680D01*
X1790085Y499525D01*
X1789977Y498225D01*
X1790085Y496926D01*
X1790410Y495771D01*
X1790843Y494905D01*
X1791493Y494184D01*
X1792359Y493895D01*
X1793225Y494184D01*
X1793875Y494905D01*
X1794308Y495771D01*
X1794633Y496926D01*
X1794741Y498225D01*
X1794633Y499525D01*
X1794308Y500680D01*
X1793875Y501546D01*
X1793225Y502267D01*
X1792359Y502556D01*
G01X1801020Y493606D02*
X1800803Y493751D01*
Y494039D01*
X1801020Y494184D01*
X1801237Y494039D01*
Y493751D01*
X1801020Y493606D01*
G01X1809681Y502556D02*
X1808815Y502267D01*
X1808165Y501546D01*
X1807732Y500680D01*
X1807407Y499525D01*
X1807299Y498225D01*
X1807407Y496926D01*
X1807732Y495771D01*
X1808165Y494905D01*
X1808815Y494184D01*
X1809681Y493895D01*
X1810547Y494184D01*
X1811197Y494905D01*
X1811630Y495771D01*
X1811955Y496926D01*
X1812063Y498225D01*
X1811955Y499525D01*
X1811630Y500680D01*
X1811197Y501546D01*
X1810547Y502267D01*
X1809681Y502556D01*
G01X1818342D02*
X1817476Y502267D01*
X1816826Y501546D01*
X1816393Y500680D01*
X1816068Y499525D01*
X1815960Y498225D01*
X1816068Y496926D01*
X1816393Y495771D01*
X1816826Y494905D01*
X1817476Y494184D01*
X1818342Y493895D01*
X1819208Y494184D01*
X1819858Y494905D01*
X1820291Y495771D01*
X1820616Y496926D01*
X1820724Y498225D01*
X1820616Y499525D01*
X1820291Y500680D01*
X1819858Y501546D01*
X1819208Y502267D01*
X1818342Y502556D01*
G01X1866827Y602635D02*
X1825920D01*
G01X1781641Y612019D02*
X1782291Y612884D01*
X1783048Y613318D01*
X1783915Y613462D01*
X1784997Y613173D01*
X1785755Y612452D01*
X1785972Y611586D01*
X1785863Y610719D01*
X1785430Y609998D01*
X1783265Y608554D01*
X1782291Y607544D01*
X1781641Y606100D01*
X1781424Y604801D01*
X1785972D01*
G01X1792359D02*
X1793117Y604945D01*
X1793983Y605378D01*
X1794524Y606100D01*
X1794741Y607111D01*
X1794524Y608121D01*
X1793875Y608987D01*
X1792900Y609420D01*
X1791818D01*
X1791168Y609709D01*
X1790627Y610431D01*
X1790410Y611441D01*
X1790735Y612452D01*
X1791493Y613173D01*
X1792359Y613462D01*
X1793225Y613173D01*
X1793983Y612452D01*
X1794308Y611441D01*
X1794091Y610431D01*
X1793550Y609709D01*
X1792900Y609420D01*
X1791818D01*
X1790843Y608987D01*
X1790194Y608121D01*
X1789977Y607111D01*
X1790194Y606100D01*
X1790735Y605378D01*
X1791601Y604945D01*
X1792359Y604801D01*
G01X1801020Y604512D02*
X1800803Y604657D01*
Y604945D01*
X1801020Y605090D01*
X1801237Y604945D01*
Y604657D01*
X1801020Y604512D01*
G01X1809681Y604801D02*
Y613462D01*
X1808382Y611730D01*
G01Y604801D02*
X1810980D01*
G01X1818125D02*
X1818342Y606677D01*
X1818667Y608265D01*
X1819100Y609709D01*
X1819641Y611297D01*
X1820507Y613462D01*
X1816177D01*
G01X1866827Y857675D02*
X1825920D01*
G01X1781857Y860850D02*
X1782615Y860129D01*
X1783481Y859840D01*
X1784348Y860129D01*
X1785105Y860995D01*
X1785647Y862294D01*
X1785863Y863593D01*
Y865181D01*
X1785647Y866480D01*
X1785105Y867635D01*
X1784456Y868212D01*
X1783698Y868501D01*
X1782832Y868212D01*
X1782182Y867635D01*
X1781749Y866769D01*
X1781533Y865614D01*
X1781749Y864604D01*
X1782291Y863593D01*
X1782940Y863016D01*
X1783698Y862871D01*
X1784564Y863160D01*
X1785214Y863882D01*
X1785863Y865181D01*
G01X1790302Y867058D02*
X1790952Y867923D01*
X1791709Y868357D01*
X1792576Y868501D01*
X1793658Y868212D01*
X1794416Y867491D01*
X1794633Y866625D01*
X1794524Y865758D01*
X1794091Y865037D01*
X1791926Y863593D01*
X1790952Y862583D01*
X1790302Y861139D01*
X1790085Y859840D01*
X1794633D01*
G01X1801020Y859551D02*
X1800803Y859696D01*
Y859984D01*
X1801020Y860129D01*
X1801237Y859984D01*
Y859696D01*
X1801020Y859551D01*
G01X1807840Y860850D02*
X1808598Y860129D01*
X1809464Y859840D01*
X1810331Y860129D01*
X1811088Y860995D01*
X1811630Y862294D01*
X1811846Y863593D01*
Y865181D01*
X1811630Y866480D01*
X1811088Y867635D01*
X1810439Y868212D01*
X1809681Y868501D01*
X1808815Y868212D01*
X1808165Y867635D01*
X1807732Y866769D01*
X1807516Y865614D01*
X1807732Y864604D01*
X1808274Y863593D01*
X1808923Y863016D01*
X1809681Y862871D01*
X1810547Y863160D01*
X1811197Y863882D01*
X1811846Y865181D01*
G01X1815960Y861139D02*
X1816610Y860417D01*
X1817368Y859984D01*
X1818342Y859840D01*
X1819316Y860129D01*
X1820074Y860706D01*
X1820616Y861716D01*
X1820724Y862871D01*
X1820507Y864026D01*
X1819966Y864748D01*
X1819208Y865325D01*
X1818450Y865470D01*
X1817692Y865325D01*
X1816718Y864748D01*
X1817043Y868501D01*
X1819966D01*
G01X1908166Y964171D02*
X1825920D01*
G01X1856736Y-792523D02*
Y-776923D01*
X1854396Y-780043D01*
G01Y-792523D02*
X1859076D01*
G01X1874636Y-776923D02*
X1873076Y-777443D01*
X1871906Y-778743D01*
X1871126Y-780303D01*
X1870541Y-782383D01*
X1870346Y-784723D01*
X1870541Y-787063D01*
X1871126Y-789143D01*
X1871906Y-790703D01*
X1873076Y-792003D01*
X1874636Y-792523D01*
X1876196Y-792003D01*
X1877366Y-790703D01*
X1878146Y-789143D01*
X1878731Y-787063D01*
X1878926Y-784723D01*
X1878731Y-782383D01*
X1878146Y-780303D01*
X1877366Y-778743D01*
X1876196Y-777443D01*
X1874636Y-776923D01*
G01X1888721Y-349875D02*
X1889010Y-350741D01*
X1889731Y-351391D01*
X1890597Y-351824D01*
X1891752Y-352149D01*
X1893052Y-352257D01*
X1894351Y-352149D01*
X1895506Y-351824D01*
X1896372Y-351391D01*
X1897093Y-350741D01*
X1897382Y-349875D01*
X1897093Y-349009D01*
X1896372Y-348359D01*
X1895506Y-347926D01*
X1894351Y-347601D01*
X1893052Y-347493D01*
X1891752Y-347601D01*
X1890597Y-347926D01*
X1889731Y-348359D01*
X1889010Y-349009D01*
X1888721Y-349875D01*
G01X1897671Y-341214D02*
X1897526Y-341431D01*
X1897238D01*
X1897093Y-341214D01*
X1897238Y-340997D01*
X1897526D01*
X1897671Y-341214D01*
G01X1888721Y-332553D02*
X1889010Y-333419D01*
X1889731Y-334069D01*
X1890597Y-334502D01*
X1891752Y-334827D01*
X1893052Y-334935D01*
X1894351Y-334827D01*
X1895506Y-334502D01*
X1896372Y-334069D01*
X1897093Y-333419D01*
X1897382Y-332553D01*
X1897093Y-331687D01*
X1896372Y-331037D01*
X1895506Y-330604D01*
X1894351Y-330279D01*
X1893052Y-330171D01*
X1891752Y-330279D01*
X1890597Y-330604D01*
X1889731Y-331037D01*
X1889010Y-331687D01*
X1888721Y-332553D01*
G01Y-323892D02*
X1889010Y-324758D01*
X1889731Y-325408D01*
X1890597Y-325841D01*
X1891752Y-326166D01*
X1893052Y-326274D01*
X1894351Y-326166D01*
X1895506Y-325841D01*
X1896372Y-325408D01*
X1897093Y-324758D01*
X1897382Y-323892D01*
X1897093Y-323026D01*
X1896372Y-322376D01*
X1895506Y-321943D01*
X1894351Y-321618D01*
X1893052Y-321510D01*
X1891752Y-321618D01*
X1890597Y-321943D01*
X1889731Y-322376D01*
X1889010Y-323026D01*
X1888721Y-323892D01*
G01X1856240Y1651D02*
Y-167680D01*
G01X1862146Y7557D02*
Y-173585D01*
G01X1886949Y-169687D02*
Y-132443D01*
G01Y-129687D02*
Y-92443D01*
G01X1862146Y-173585D02*
X1856240Y-167680D01*
G01X1862146Y-173585D02*
X1895610D01*
G01X1862146Y-169687D02*
X1886949D01*
G01Y-132443D02*
X1862146D01*
G01Y-129687D02*
X1886949D01*
G01Y-89687D02*
Y-52443D01*
G01Y-92443D02*
X1862146D01*
G01Y-89687D02*
X1886949D01*
G01Y-49687D02*
Y-12443D01*
G01Y-52443D02*
X1862146D01*
G01Y-49687D02*
X1886949D01*
G01Y-12443D02*
X1862146D01*
G01X1856240Y75549D02*
Y16218D01*
G01X1862146Y81454D02*
Y10313D01*
G01X1881831Y16139D02*
Y19289D01*
G01Y21139D02*
Y24289D01*
G01Y26139D02*
Y29289D01*
G01Y31139D02*
Y34289D01*
G01Y36139D02*
Y39289D01*
G01Y41139D02*
Y44289D01*
G01X1886949Y-9687D02*
Y7557D01*
G01X1862146D02*
X1856240Y1651D01*
G01X1862146Y10313D02*
X1856240Y16218D01*
G01X1862146Y-9687D02*
X1886949D01*
G01X1862146Y7557D02*
X1898169D01*
G01X1862146Y10313D02*
X1898169D01*
G01X1862146Y16139D02*
X1881831D01*
G01Y19289D02*
X1862146D01*
G01Y21139D02*
X1881831D01*
G01Y24289D02*
X1862146D01*
G01Y26139D02*
X1881831D01*
G01Y29289D02*
X1862146D01*
G01Y31139D02*
X1881831D01*
G01Y34289D02*
X1862146D01*
G01Y36139D02*
X1881831D01*
G01Y39289D02*
X1862146D01*
G01Y41139D02*
X1881831D01*
G01Y44289D02*
X1862146D01*
G01Y81454D02*
X1856240Y75549D01*
G01X1881831Y46139D02*
Y49289D01*
G01Y51139D02*
Y54289D01*
G01Y56139D02*
Y59289D01*
G01Y61139D02*
Y64289D01*
G01Y66139D02*
Y69289D01*
G01Y71139D02*
Y74289D01*
G01X1862146Y46139D02*
X1881831D01*
G01Y49289D02*
X1862146D01*
G01Y51139D02*
X1881831D01*
G01Y54289D02*
X1862146D01*
G01Y56139D02*
X1881831D01*
G01Y59289D02*
X1862146D01*
G01Y61139D02*
X1881831D01*
G01Y64289D02*
X1862146D01*
G01Y66139D02*
X1881831D01*
G01Y69289D02*
X1862146D01*
G01Y71139D02*
X1881831D01*
G01Y74289D02*
X1862146D01*
G01X1895610Y81454D02*
X1862146D01*
G01X1924158Y135115D02*
X1851276Y190972D01*
G01D02*
X1848126D01*
G01X1862693Y405501D02*
X1854032D01*
X1855764Y404202D01*
G01X1862693D02*
Y406800D01*
G01Y414162D02*
X1854032D01*
X1855764Y412863D01*
G01X1862693D02*
Y415461D01*
G01X1862982Y422823D02*
X1862837Y422606D01*
X1862549D01*
X1862404Y422823D01*
X1862549Y423040D01*
X1862837D01*
X1862982Y422823D01*
G01X1854032Y431484D02*
X1854321Y430618D01*
X1855042Y429968D01*
X1855908Y429535D01*
X1857063Y429210D01*
X1858363Y429102D01*
X1859662Y429210D01*
X1860817Y429535D01*
X1861683Y429968D01*
X1862404Y430618D01*
X1862693Y431484D01*
X1862404Y432350D01*
X1861683Y433000D01*
X1860817Y433433D01*
X1859662Y433758D01*
X1858363Y433866D01*
X1857063Y433758D01*
X1855908Y433433D01*
X1855042Y433000D01*
X1854321Y432350D01*
X1854032Y431484D01*
G01Y440145D02*
X1854321Y439279D01*
X1855042Y438629D01*
X1855908Y438196D01*
X1857063Y437871D01*
X1858363Y437763D01*
X1859662Y437871D01*
X1860817Y438196D01*
X1861683Y438629D01*
X1862404Y439279D01*
X1862693Y440145D01*
X1862404Y441011D01*
X1861683Y441661D01*
X1860817Y442094D01*
X1859662Y442419D01*
X1858363Y442527D01*
X1857063Y442419D01*
X1855908Y442094D01*
X1855042Y441661D01*
X1854321Y441011D01*
X1854032Y440145D01*
G01X1864859Y604604D02*
Y447724D01*
G01Y777872D02*
Y608541D01*
G01X1870764Y783777D02*
Y602635D01*
G01X1864859Y608541D02*
X1870764Y602635D01*
G01D02*
X1904229D01*
G01X1870764Y606533D02*
X1895567D01*
G01Y643777D02*
X1870764D01*
G01Y646533D02*
X1895567D01*
G01Y683777D02*
X1870764D01*
G01Y686533D02*
X1895567D01*
G01Y723777D02*
X1870764D01*
G01Y726533D02*
X1895567D01*
G01X1870764Y857675D02*
Y786533D01*
G01Y783777D02*
X1864859Y777872D01*
G01Y792439D02*
X1870764Y786533D01*
G01X1895567Y763777D02*
X1870764D01*
G01Y766533D02*
X1895567D01*
G01X1870764Y783777D02*
X1906788D01*
G01X1870764Y786533D02*
X1906788D01*
G01X1864859Y851769D02*
Y792439D01*
G01X1890449Y792360D02*
Y795509D01*
G01Y797360D02*
Y800509D01*
G01Y802360D02*
Y805509D01*
G01Y807360D02*
Y810509D01*
G01Y812360D02*
Y815509D01*
G01Y817360D02*
Y820509D01*
G01Y822360D02*
Y825509D01*
G01Y827360D02*
Y830509D01*
G01Y832360D02*
Y835509D01*
G01Y837360D02*
Y840509D01*
G01Y842360D02*
Y845509D01*
G01X1870764Y792360D02*
X1890449D01*
G01Y795509D02*
X1870764D01*
G01Y797360D02*
X1890449D01*
G01Y800509D02*
X1870764D01*
G01Y802360D02*
X1890449D01*
G01Y805509D02*
X1870764D01*
G01Y807360D02*
X1890449D01*
G01Y810509D02*
X1870764D01*
G01Y812360D02*
X1890449D01*
G01Y815509D02*
X1870764D01*
G01Y817360D02*
X1890449D01*
G01Y820509D02*
X1870764D01*
G01Y822360D02*
X1890449D01*
G01Y825509D02*
X1870764D01*
G01Y827360D02*
X1890449D01*
G01Y830509D02*
X1870764D01*
G01Y832360D02*
X1890449D01*
G01Y835509D02*
X1870764D01*
G01Y837360D02*
X1890449D01*
G01Y840509D02*
X1870764D01*
G01Y842360D02*
X1890449D01*
G01Y845509D02*
X1870764D01*
G01Y857675D02*
X1864859Y851769D01*
G01X1890449Y847360D02*
Y850509D01*
G01X1870764Y847360D02*
X1890449D01*
G01Y850509D02*
X1870764D01*
G01X1904229Y857675D02*
X1870764D01*
G01X1856736Y1385233D02*
Y1400833D01*
X1854396Y1397713D01*
G01Y1385233D02*
X1859076D01*
G01X1874636Y1400833D02*
X1873076Y1400313D01*
X1871906Y1399013D01*
X1871126Y1397453D01*
X1870541Y1395373D01*
X1870346Y1393033D01*
X1870541Y1390693D01*
X1871126Y1388613D01*
X1871906Y1387053D01*
X1873076Y1385753D01*
X1874636Y1385233D01*
X1876196Y1385753D01*
X1877366Y1387053D01*
X1878146Y1388613D01*
X1878731Y1390693D01*
X1878926Y1393033D01*
X1878731Y1395373D01*
X1878146Y1397453D01*
X1877366Y1399013D01*
X1876196Y1400313D01*
X1874636Y1400833D01*
G01X1899547Y-284491D02*
Y-316313D01*
G01Y-280554D02*
Y184013D01*
G01X2536004Y-284491D02*
X1903484D01*
G01X1962539Y-268743D02*
X1899547D01*
G01X1947421Y-223467D02*
G03I-17716J0D01*
G01X1899547Y-280554D02*
G03X1903484Y-284491I3937J0D01*
G01X1936693Y-223467D02*
G03I-6988J0D01*
G01X1899547Y-177522D02*
G03X1895610Y-173585I-3937J0D01*
G01X1916791Y-58113D02*
Y-38428D01*
G01X1928602D02*
Y-58113D01*
G01X1924665Y-62050D02*
X1920728D01*
G01Y-34491D02*
X1924665D01*
G01X1916791Y-58113D02*
G03X1920728Y-62050I3937J0D01*
G01X1924665D02*
G03X1928602Y-58113I0J3937D01*
G01Y-38428D02*
G03X1924665Y-34491I-3937J0D01*
G01X1920728D02*
G03X1916791Y-38428I0J-3937D01*
G01X1898169Y7557D02*
G03Y10313I0J1378D01*
G01X1895610Y81454D02*
G03X1899547Y85391I0J3937D01*
G01X1947421Y130864D02*
G03I-17716J0D01*
G01X1936693D02*
G03I-6988J0D01*
G01X1941146Y144391D02*
X1996262Y209560D01*
G01X1962539Y172202D02*
X1899547D01*
G01X1903484Y187950D02*
X2536004D01*
G01X1903484D02*
G03X1899547Y184013I0J-3937D01*
G01X1897339Y414162D02*
X1897628Y413296D01*
X1898349Y412646D01*
X1899215Y412213D01*
X1900370Y411888D01*
X1901670Y411780D01*
X1902969Y411888D01*
X1904124Y412213D01*
X1904990Y412646D01*
X1905711Y413296D01*
X1906000Y414162D01*
X1905711Y415028D01*
X1904990Y415678D01*
X1904124Y416111D01*
X1902969Y416436D01*
X1901670Y416544D01*
X1900370Y416436D01*
X1899215Y416111D01*
X1898349Y415678D01*
X1897628Y415028D01*
X1897339Y414162D01*
G01X1906289Y422823D02*
X1906144Y422606D01*
X1905856D01*
X1905711Y422823D01*
X1905856Y423040D01*
X1906144D01*
X1906289Y422823D01*
G01X1897339Y431484D02*
X1897628Y430618D01*
X1898349Y429968D01*
X1899215Y429535D01*
X1900370Y429210D01*
X1901670Y429102D01*
X1902969Y429210D01*
X1904124Y429535D01*
X1904990Y429968D01*
X1905711Y430618D01*
X1906000Y431484D01*
X1905711Y432350D01*
X1904990Y433000D01*
X1904124Y433433D01*
X1902969Y433758D01*
X1901670Y433866D01*
X1900370Y433758D01*
X1899215Y433433D01*
X1898349Y433000D01*
X1897628Y432350D01*
X1897339Y431484D01*
G01Y440145D02*
X1897628Y439279D01*
X1898349Y438629D01*
X1899215Y438196D01*
X1900370Y437871D01*
X1901670Y437763D01*
X1902969Y437871D01*
X1904124Y438196D01*
X1904990Y438629D01*
X1905711Y439279D01*
X1906000Y440145D01*
X1905711Y441011D01*
X1904990Y441661D01*
X1904124Y442094D01*
X1902969Y442419D01*
X1901670Y442527D01*
X1900370Y442419D01*
X1899215Y442094D01*
X1898349Y441661D01*
X1897628Y441011D01*
X1897339Y440145D01*
G01X1908166Y495667D02*
Y598698D01*
G01X2544622Y491730D02*
X1912103D01*
G01X1908166Y495667D02*
G03X1912103Y491730I3937J0D01*
G01X1908166D02*
Y447724D01*
G01X1938323Y535037D02*
X1908166D01*
G01X1938323D02*
G03Y570470I0J17717D01*
G01X1945311Y552753D02*
G03I-6988J0D01*
G01X1895567Y606533D02*
Y643777D01*
G01X1938323Y570470D02*
X1908166D01*
G01Y598698D02*
G03X1904229Y602635I-3937J0D01*
G01X1895567Y646533D02*
Y683777D01*
G01Y686533D02*
Y723777D01*
G01Y726533D02*
Y763777D01*
G01X1925410Y718108D02*
Y737793D01*
G01X1937221D02*
Y718108D01*
G01X1933284Y714171D02*
X1929347D01*
G01X1925410Y718108D02*
G03X1929347Y714171I3937J0D01*
G01X1933284D02*
G03X1937221Y718108I0J3937D01*
G01X1895567Y766533D02*
Y783777D01*
G01X1929347Y741730D02*
X1933284D01*
G01X1937221Y737793D02*
G03X1933284Y741730I-3937J0D01*
G01X1929347D02*
G03X1925410Y737793I0J-3937D01*
G01X1906788Y783777D02*
G03Y786533I0J1378D01*
G01X1908166Y861612D02*
Y960234D01*
G01X1938323Y889368D02*
X1908166D01*
G01X1938323D02*
G03Y924801I0J17717D01*
G01X1945311Y907084D02*
G03I-6988J0D01*
G01X1904229Y857675D02*
G03X1908166Y861612I0J3937D01*
G01X1938323Y924801D02*
X1908166D01*
G01X1912103Y964171D02*
X2544622D01*
G01X1912103D02*
G03X1908166Y960234I0J-3937D01*
G01X1967160Y-777373D02*
Y-796310D01*
G01X1962539Y-268743D02*
Y172202D01*
G01X1996262Y209560D02*
X1999411D01*
G01D02*
X2075054D01*
G01X1954978Y929385D02*
X2038091Y1016267D01*
G01X1967160Y1400383D02*
Y1381446D01*
G01X2032337Y-693460D02*
Y-753628D01*
G01D02*
X2784437D01*
G01X2032337Y-693460D02*
Y-648334D01*
G01X2822042Y-693460D02*
X2032337D01*
G01Y-648334D02*
Y-603208D01*
G01Y-648334D02*
X2408387D01*
G01X2045423Y-615487D02*
X2051673Y-635487D01*
X2057923Y-615487D01*
G01X2067923Y-626487D02*
X2075923D01*
X2075173Y-624154D01*
X2073923Y-622821D01*
X2072173Y-622154D01*
X2070423Y-622487D01*
X2068923Y-623487D01*
X2067923Y-625821D01*
X2067423Y-627821D01*
Y-629820D01*
X2067923Y-631821D01*
X2069173Y-633821D01*
X2070673Y-635154D01*
X2072423Y-635487D01*
X2074173Y-634820D01*
X2075923Y-632821D01*
G01X2088173Y-635487D02*
Y-622154D01*
G01Y-624820D02*
X2089423Y-623487D01*
X2090673Y-622487D01*
X2092423Y-622154D01*
X2093673Y-622487D01*
X2095173Y-623487D01*
G01X2107923Y-633154D02*
X2109173Y-634487D01*
X2110923Y-635487D01*
X2112423D01*
X2113923Y-634820D01*
X2114923Y-633821D01*
X2115423Y-632488D01*
X2115173Y-630487D01*
X2114173Y-629487D01*
X2109673Y-627487D01*
X2108673Y-625153D01*
X2109173Y-623487D01*
X2110173Y-622487D01*
X2111673Y-622154D01*
X2113173Y-622487D01*
X2114673Y-623487D01*
G01X2131673Y-622154D02*
Y-635487D01*
G01Y-616821D02*
X2131173Y-616487D01*
Y-615820D01*
X2131673Y-615487D01*
X2132173Y-615820D01*
Y-616487D01*
X2131673Y-616821D01*
G01X2151673Y-635487D02*
X2150173Y-635154D01*
X2148673Y-633821D01*
X2147673Y-631487D01*
X2147173Y-628821D01*
X2147673Y-626154D01*
X2148673Y-623820D01*
X2150173Y-622487D01*
X2151673Y-622154D01*
X2153173Y-622487D01*
X2154673Y-623820D01*
X2155673Y-626154D01*
X2155923Y-628821D01*
X2155673Y-631487D01*
X2154673Y-633821D01*
X2153173Y-635154D01*
X2151673Y-635487D01*
G01X2167423D02*
Y-622154D01*
G01Y-625487D02*
X2168423Y-623820D01*
X2169923Y-622487D01*
X2171923Y-622154D01*
X2173673Y-622487D01*
X2175173Y-623820D01*
X2175923Y-626154D01*
Y-635487D01*
G01X2059875Y-666062D02*
X2058375Y-665062D01*
X2056625Y-664395D01*
X2054625D01*
X2052375Y-665395D01*
X2050625Y-667062D01*
X2049375Y-669062D01*
X2048375Y-672395D01*
X2048125Y-675395D01*
X2048625Y-678395D01*
X2049375Y-680395D01*
X2050875Y-682395D01*
X2052625Y-683728D01*
X2054375Y-684395D01*
X2056125D01*
X2057875Y-683728D01*
X2059375Y-682729D01*
X2060625Y-681396D01*
G01X2070875Y-684395D02*
Y-671062D01*
G01Y-673728D02*
X2072125Y-672395D01*
X2073375Y-671395D01*
X2075125Y-671062D01*
X2076375Y-671395D01*
X2077875Y-672395D01*
G01X2090625Y-675395D02*
X2098625D01*
X2097875Y-673062D01*
X2096625Y-671729D01*
X2094875Y-671062D01*
X2093125Y-671395D01*
X2091625Y-672395D01*
X2090625Y-674729D01*
X2090125Y-676729D01*
Y-678728D01*
X2090625Y-680729D01*
X2091875Y-682729D01*
X2093375Y-684062D01*
X2095125Y-684395D01*
X2096875Y-683728D01*
X2098625Y-681729D01*
G01X2118875Y-684395D02*
Y-671062D01*
G01Y-673395D02*
X2117875Y-672062D01*
X2116375Y-671395D01*
X2114625Y-671062D01*
X2112875Y-671729D01*
X2111375Y-673062D01*
X2110375Y-675062D01*
X2109875Y-677729D01*
X2110375Y-680395D01*
X2111375Y-682395D01*
X2112875Y-683728D01*
X2114625Y-684395D01*
X2116375Y-684062D01*
X2117875Y-683062D01*
X2118875Y-681729D01*
G01X2134375Y-664395D02*
Y-684395D01*
G01X2130875Y-671062D02*
X2137875D01*
G01X2150625Y-675395D02*
X2158625D01*
X2157875Y-673062D01*
X2156625Y-671729D01*
X2154875Y-671062D01*
X2153125Y-671395D01*
X2151625Y-672395D01*
X2150625Y-674729D01*
X2150125Y-676729D01*
Y-678728D01*
X2150625Y-680729D01*
X2151875Y-682729D01*
X2153375Y-684062D01*
X2155125Y-684395D01*
X2156875Y-683728D01*
X2158625Y-681729D01*
G01X2178875Y-664395D02*
Y-684395D01*
G01Y-681396D02*
X2177875Y-683062D01*
X2176375Y-684062D01*
X2174625Y-684395D01*
X2172625Y-683728D01*
X2171125Y-682062D01*
X2170125Y-680062D01*
X2169875Y-677729D01*
X2170125Y-675395D01*
X2171125Y-673395D01*
X2172625Y-671729D01*
X2174625Y-671062D01*
X2176375Y-671395D01*
X2177625Y-672062D01*
X2178875Y-673395D01*
G01X2032337Y-603208D02*
Y-497938D01*
G01Y-603208D02*
X2822042D01*
G01X2049375Y-591473D02*
Y-571473D01*
X2055375D01*
X2057375Y-572473D01*
X2058875Y-574806D01*
X2059375Y-577473D01*
X2058875Y-580140D01*
X2057625Y-582140D01*
X2055375Y-583140D01*
X2049375D01*
G01X2079875Y-573140D02*
X2078375Y-572140D01*
X2076625Y-571473D01*
X2074625D01*
X2072375Y-572473D01*
X2070625Y-574140D01*
X2069375Y-576140D01*
X2068375Y-579473D01*
X2068125Y-582473D01*
X2068625Y-585473D01*
X2069375Y-587473D01*
X2070875Y-589473D01*
X2072625Y-590806D01*
X2074375Y-591473D01*
X2076125D01*
X2077875Y-590806D01*
X2079375Y-589807D01*
X2080625Y-588474D01*
G01X2096375Y-580806D02*
X2097375Y-579806D01*
X2098125Y-578140D01*
X2098625Y-575806D01*
X2098125Y-573806D01*
X2097125Y-572473D01*
X2095375Y-571473D01*
X2088625D01*
Y-591473D01*
X2096875D01*
X2098625Y-590140D01*
X2099625Y-588140D01*
X2100125Y-585806D01*
X2099625Y-583473D01*
X2098125Y-581473D01*
X2096375Y-580806D01*
X2088625D01*
G01X2128625Y-591473D02*
Y-571473D01*
X2140125Y-591473D01*
Y-571473D01*
G01X2154375Y-591473D02*
X2152875Y-591140D01*
X2151375Y-589807D01*
X2150375Y-587473D01*
X2149875Y-584807D01*
X2150375Y-582140D01*
X2151375Y-579806D01*
X2152875Y-578473D01*
X2154375Y-578140D01*
X2155875Y-578473D01*
X2157375Y-579806D01*
X2158375Y-582140D01*
X2158625Y-584807D01*
X2158375Y-587473D01*
X2157375Y-589807D01*
X2155875Y-591140D01*
X2154375Y-591473D01*
G01X2174375Y-592140D02*
X2173875Y-591806D01*
Y-591140D01*
X2174375Y-590806D01*
X2174875Y-591140D01*
Y-591806D01*
X2174375Y-592140D01*
G01X2032337Y-558082D02*
X2822042D01*
G01X2057820Y-547260D02*
Y-522260D01*
X2066010Y-543093D01*
X2074200Y-522260D01*
Y-547260D01*
G01X2091210D02*
X2089320Y-546843D01*
X2087430Y-545177D01*
X2086170Y-542260D01*
X2085540Y-538927D01*
X2086170Y-535594D01*
X2087430Y-532677D01*
X2089320Y-531010D01*
X2091210Y-530594D01*
X2093100Y-531010D01*
X2094990Y-532677D01*
X2096250Y-535594D01*
X2096565Y-538927D01*
X2096250Y-542260D01*
X2094990Y-545177D01*
X2093100Y-546843D01*
X2091210Y-547260D01*
G01X2122080Y-522260D02*
Y-547260D01*
G01Y-543511D02*
X2120820Y-545594D01*
X2118930Y-546843D01*
X2116725Y-547260D01*
X2114205Y-546427D01*
X2112315Y-544344D01*
X2111055Y-541844D01*
X2110740Y-538927D01*
X2111055Y-536010D01*
X2112315Y-533510D01*
X2114205Y-531427D01*
X2116725Y-530594D01*
X2118930Y-531010D01*
X2120505Y-531844D01*
X2122080Y-533510D01*
G01X2136885Y-536010D02*
X2146965D01*
X2146020Y-533093D01*
X2144445Y-531427D01*
X2142240Y-530594D01*
X2140035Y-531010D01*
X2138145Y-532260D01*
X2136885Y-535177D01*
X2136255Y-537677D01*
Y-540177D01*
X2136885Y-542677D01*
X2138460Y-545177D01*
X2140350Y-546843D01*
X2142555Y-547260D01*
X2144760Y-546427D01*
X2146965Y-543927D01*
G01X2166810Y-547260D02*
Y-522260D01*
G01X2032337Y-497938D02*
X2822042D01*
G01X2012620Y211725D02*
Y220386D01*
X2008614Y214179D01*
X2014028D01*
G01X2017708Y211725D02*
X2022256Y220386D01*
G01X2017708D02*
X2022256Y211725D01*
G01X2025070D02*
Y217499D01*
G01Y216055D02*
X2025504Y216777D01*
X2026153Y217355D01*
X2027019Y217499D01*
X2027777Y217355D01*
X2028427Y216777D01*
X2028752Y215767D01*
Y211725D01*
G01X2036619Y212735D02*
X2037377Y212014D01*
X2038243Y211725D01*
X2039110Y212014D01*
X2039867Y212880D01*
X2040409Y214179D01*
X2040625Y215478D01*
Y217066D01*
X2040409Y218365D01*
X2039867Y219520D01*
X2039218Y220097D01*
X2038460Y220386D01*
X2037594Y220097D01*
X2036944Y219520D01*
X2036511Y218654D01*
X2036295Y217499D01*
X2036511Y216489D01*
X2037053Y215478D01*
X2037702Y214901D01*
X2038460Y214756D01*
X2039326Y215045D01*
X2039976Y215767D01*
X2040625Y217066D01*
G01X2047121Y211436D02*
X2046904Y211581D01*
Y211869D01*
X2047121Y212014D01*
X2047338Y211869D01*
Y211581D01*
X2047121Y211436D01*
G01X2055782Y220386D02*
X2054916Y220097D01*
X2054266Y219376D01*
X2053833Y218510D01*
X2053508Y217355D01*
X2053400Y216055D01*
X2053508Y214756D01*
X2053833Y213601D01*
X2054266Y212735D01*
X2054916Y212014D01*
X2055782Y211725D01*
X2056648Y212014D01*
X2057298Y212735D01*
X2057731Y213601D01*
X2058056Y214756D01*
X2058164Y216055D01*
X2058056Y217355D01*
X2057731Y218510D01*
X2057298Y219376D01*
X2056648Y220097D01*
X2055782Y220386D01*
G01X2064443D02*
X2063577Y220097D01*
X2062927Y219376D01*
X2062494Y218510D01*
X2062169Y217355D01*
X2062061Y216055D01*
X2062169Y214756D01*
X2062494Y213601D01*
X2062927Y212735D01*
X2063577Y212014D01*
X2064443Y211725D01*
X2065309Y212014D01*
X2065959Y212735D01*
X2066392Y213601D01*
X2066717Y214756D01*
X2066825Y216055D01*
X2066717Y217355D01*
X2066392Y218510D01*
X2065959Y219376D01*
X2065309Y220097D01*
X2064443Y220386D01*
G01X2038091Y1016267D02*
X2049902D01*
G01X2051093Y1019155D02*
X2051743Y1020020D01*
X2052500Y1020454D01*
X2053367Y1020598D01*
X2054449Y1020309D01*
X2055207Y1019588D01*
X2055424Y1018722D01*
X2055315Y1017855D01*
X2054882Y1017134D01*
X2052717Y1015690D01*
X2051743Y1014680D01*
X2051093Y1013236D01*
X2050876Y1011937D01*
X2055424D01*
G01X2060187Y1017711D02*
X2063435Y1011937D01*
G01Y1017711D02*
X2060187Y1011937D01*
G01X2076643D02*
Y1020598D01*
X2081623Y1011937D01*
Y1020598D01*
G01X2087794Y1011937D02*
X2086928Y1012081D01*
X2086170Y1012659D01*
X2085520Y1013525D01*
X2085087Y1014535D01*
X2084871Y1015690D01*
Y1016845D01*
X2085087Y1018000D01*
X2085520Y1019010D01*
X2086170Y1019876D01*
X2086928Y1020454D01*
X2087794Y1020598D01*
X2088660Y1020454D01*
X2089418Y1019876D01*
X2090068Y1019010D01*
X2090501Y1018000D01*
X2090717Y1016845D01*
Y1015690D01*
X2090501Y1014535D01*
X2090068Y1013525D01*
X2089418Y1012659D01*
X2088660Y1012081D01*
X2087794Y1011937D01*
G01X2107498Y1019876D02*
X2106848Y1020309D01*
X2106090Y1020598D01*
X2105224D01*
X2104250Y1020165D01*
X2103492Y1019443D01*
X2102951Y1018577D01*
X2102517Y1017134D01*
X2102409Y1015834D01*
X2102626Y1014535D01*
X2102951Y1013669D01*
X2103600Y1012803D01*
X2104358Y1012226D01*
X2105116Y1011937D01*
X2105874D01*
X2106632Y1012226D01*
X2107281Y1012659D01*
X2107823Y1013236D01*
G01X2113777Y1011937D02*
X2112911Y1012081D01*
X2112153Y1012659D01*
X2111503Y1013525D01*
X2111070Y1014535D01*
X2110854Y1015690D01*
Y1016845D01*
X2111070Y1018000D01*
X2111503Y1019010D01*
X2112153Y1019876D01*
X2112911Y1020454D01*
X2113777Y1020598D01*
X2114643Y1020454D01*
X2115401Y1019876D01*
X2116051Y1019010D01*
X2116484Y1018000D01*
X2116700Y1016845D01*
Y1015690D01*
X2116484Y1014535D01*
X2116051Y1013525D01*
X2115401Y1012659D01*
X2114643Y1012081D01*
X2113777Y1011937D01*
G01X2119623D02*
Y1020598D01*
X2122438Y1013380D01*
X2125253Y1020598D01*
Y1011937D01*
G01X2128934D02*
Y1020598D01*
X2131532D01*
X2132398Y1020165D01*
X2133048Y1019155D01*
X2133264Y1018000D01*
X2133048Y1016845D01*
X2132506Y1015979D01*
X2131532Y1015546D01*
X2128934D01*
G01X2139760Y1011937D02*
X2138894Y1012081D01*
X2138136Y1012659D01*
X2137486Y1013525D01*
X2137053Y1014535D01*
X2136837Y1015690D01*
Y1016845D01*
X2137053Y1018000D01*
X2137486Y1019010D01*
X2138136Y1019876D01*
X2138894Y1020454D01*
X2139760Y1020598D01*
X2140626Y1020454D01*
X2141384Y1019876D01*
X2142034Y1019010D01*
X2142467Y1018000D01*
X2142683Y1016845D01*
Y1015690D01*
X2142467Y1014535D01*
X2142034Y1013525D01*
X2141384Y1012659D01*
X2140626Y1012081D01*
X2139760Y1011937D01*
G01X2145931D02*
Y1020598D01*
X2150911Y1011937D01*
Y1020598D01*
G01X2159247Y1011937D02*
X2154917D01*
Y1020598D01*
X2159247D01*
G01X2157515Y1016412D02*
X2154917D01*
G01X2163253Y1011937D02*
Y1020598D01*
X2168233Y1011937D01*
Y1020598D01*
G01X2174404D02*
Y1011937D01*
G01X2171914Y1020598D02*
X2176894D01*
G01X2194974Y1009050D02*
X2189561Y1017711D01*
Y1019155D01*
X2190643Y1020598D01*
X2191726D01*
X2192809Y1019155D01*
Y1017711D01*
X2191726Y1016267D01*
X2189561Y1014824D01*
X2188478Y1013380D01*
Y1010494D01*
X2189561Y1009050D01*
X2192809D01*
X2194974Y1011937D01*
G01X2209048Y1020598D02*
Y1011937D01*
G01X2206558Y1020598D02*
X2211538D01*
G01X2215544Y1011937D02*
Y1020598D01*
X2218250D01*
X2219116Y1020165D01*
X2219658Y1019588D01*
X2219874Y1018433D01*
X2219658Y1017278D01*
X2219008Y1016556D01*
X2218250Y1016123D01*
X2215544D01*
G01X2218250D02*
X2219874Y1011937D01*
G01X2223663D02*
X2226370Y1020598D01*
X2229077Y1011937D01*
G01X2228102Y1014968D02*
X2224638D01*
G01X2237413Y1019876D02*
X2236763Y1020309D01*
X2236005Y1020598D01*
X2235139D01*
X2234165Y1020165D01*
X2233407Y1019443D01*
X2232866Y1018577D01*
X2232432Y1017134D01*
X2232324Y1015834D01*
X2232541Y1014535D01*
X2232866Y1013669D01*
X2233515Y1012803D01*
X2234273Y1012226D01*
X2235031Y1011937D01*
X2235789D01*
X2236547Y1012226D01*
X2237196Y1012659D01*
X2237738Y1013236D01*
G01X2245857Y1011937D02*
X2241527D01*
Y1020598D01*
X2245857D01*
G01X2244125Y1016412D02*
X2241527D01*
G01X2053150Y998944D02*
X2052284Y999088D01*
X2051526Y999666D01*
X2050876Y1000532D01*
X2050443Y1001542D01*
X2050227Y1002697D01*
Y1003852D01*
X2050443Y1005007D01*
X2050876Y1006017D01*
X2051526Y1006883D01*
X2052284Y1007461D01*
X2053150Y1007605D01*
X2054016Y1007461D01*
X2054774Y1006883D01*
X2055424Y1006017D01*
X2055857Y1005007D01*
X2056073Y1003852D01*
Y1002697D01*
X2055857Y1001542D01*
X2055424Y1000532D01*
X2054774Y999666D01*
X2054016Y999088D01*
X2053150Y998944D01*
G01X2059321D02*
Y1007605D01*
X2064301Y998944D01*
Y1007605D01*
G01X2081515Y1006883D02*
X2080865Y1007316D01*
X2080107Y1007605D01*
X2079241D01*
X2078267Y1007172D01*
X2077509Y1006450D01*
X2076968Y1005584D01*
X2076534Y1004141D01*
X2076426Y1002841D01*
X2076643Y1001542D01*
X2076968Y1000676D01*
X2077617Y999810D01*
X2078375Y999233D01*
X2079133Y998944D01*
X2079891D01*
X2080649Y999233D01*
X2081298Y999666D01*
X2081840Y1000243D01*
G01X2087794Y998944D02*
X2086928Y999088D01*
X2086170Y999666D01*
X2085520Y1000532D01*
X2085087Y1001542D01*
X2084871Y1002697D01*
Y1003852D01*
X2085087Y1005007D01*
X2085520Y1006017D01*
X2086170Y1006883D01*
X2086928Y1007461D01*
X2087794Y1007605D01*
X2088660Y1007461D01*
X2089418Y1006883D01*
X2090068Y1006017D01*
X2090501Y1005007D01*
X2090717Y1003852D01*
Y1002697D01*
X2090501Y1001542D01*
X2090068Y1000532D01*
X2089418Y999666D01*
X2088660Y999088D01*
X2087794Y998944D01*
G01X2093640D02*
Y1007605D01*
X2096455Y1000387D01*
X2099270Y1007605D01*
Y998944D01*
G01X2102951D02*
Y1007605D01*
X2105549D01*
X2106415Y1007172D01*
X2107065Y1006162D01*
X2107281Y1005007D01*
X2107065Y1003852D01*
X2106523Y1002986D01*
X2105549Y1002553D01*
X2102951D01*
G01X2113777Y998944D02*
X2112911Y999088D01*
X2112153Y999666D01*
X2111503Y1000532D01*
X2111070Y1001542D01*
X2110854Y1002697D01*
Y1003852D01*
X2111070Y1005007D01*
X2111503Y1006017D01*
X2112153Y1006883D01*
X2112911Y1007461D01*
X2113777Y1007605D01*
X2114643Y1007461D01*
X2115401Y1006883D01*
X2116051Y1006017D01*
X2116484Y1005007D01*
X2116700Y1003852D01*
Y1002697D01*
X2116484Y1001542D01*
X2116051Y1000532D01*
X2115401Y999666D01*
X2114643Y999088D01*
X2113777Y998944D01*
G01X2119948D02*
Y1007605D01*
X2124928Y998944D01*
Y1007605D01*
G01X2133264Y998944D02*
X2128934D01*
Y1007605D01*
X2133264D01*
G01X2131532Y1003419D02*
X2128934D01*
G01X2137270Y998944D02*
Y1007605D01*
X2142250Y998944D01*
Y1007605D01*
G01X2148421D02*
Y998944D01*
G01X2145931Y1007605D02*
X2150911D01*
G01X2163469Y1000099D02*
X2164336Y999377D01*
X2165310Y998944D01*
X2166176D01*
X2167042Y999377D01*
X2167692Y1000099D01*
X2168017Y1001109D01*
X2167800Y1002120D01*
X2167259Y1002986D01*
X2166284Y1003563D01*
X2164985Y1003852D01*
X2164227Y1004429D01*
X2163902Y1005440D01*
X2164119Y1006450D01*
X2164660Y1007172D01*
X2165418Y1007605D01*
X2166176D01*
X2166934Y1007316D01*
X2167584Y1006595D01*
G01X2173105Y1007605D02*
X2175703D01*
G01X2174404D02*
Y998944D01*
G01X2173105D02*
X2175703D01*
G01X2180683D02*
Y1007605D01*
X2182848D01*
X2183715Y1007172D01*
X2184364Y1006595D01*
X2184906Y1005729D01*
X2185339Y1004718D01*
X2185447Y1003274D01*
X2185339Y1001831D01*
X2184906Y1000820D01*
X2184364Y999954D01*
X2183715Y999377D01*
X2182848Y998944D01*
X2180683D01*
G01X2193891D02*
X2189561D01*
Y1007605D01*
X2193891D01*
G01X2192159Y1003419D02*
X2189561D01*
G01X2206341Y998944D02*
X2209048Y1007605D01*
X2211755Y998944D01*
G01X2210780Y1001975D02*
X2207316D01*
G01X2215219Y998944D02*
Y1007605D01*
X2220199Y998944D01*
Y1007605D01*
G01X2223988Y998944D02*
Y1007605D01*
X2226153D01*
X2227020Y1007172D01*
X2227669Y1006595D01*
X2228211Y1005729D01*
X2228644Y1004718D01*
X2228752Y1003274D01*
X2228644Y1001831D01*
X2228211Y1000820D01*
X2227669Y999954D01*
X2227020Y999377D01*
X2226153Y998944D01*
X2223988D01*
G01X2241418Y1000099D02*
X2242285Y999377D01*
X2243259Y998944D01*
X2244125D01*
X2244991Y999377D01*
X2245641Y1000099D01*
X2245966Y1001109D01*
X2245749Y1002120D01*
X2245208Y1002986D01*
X2244233Y1003563D01*
X2242934Y1003852D01*
X2242176Y1004429D01*
X2241851Y1005440D01*
X2242068Y1006450D01*
X2242609Y1007172D01*
X2243367Y1007605D01*
X2244125D01*
X2244883Y1007316D01*
X2245533Y1006595D01*
G01X2252353Y998944D02*
X2251487Y999088D01*
X2250729Y999666D01*
X2250079Y1000532D01*
X2249646Y1001542D01*
X2249430Y1002697D01*
Y1003852D01*
X2249646Y1005007D01*
X2250079Y1006017D01*
X2250729Y1006883D01*
X2251487Y1007461D01*
X2252353Y1007605D01*
X2253219Y1007461D01*
X2253977Y1006883D01*
X2254627Y1006017D01*
X2255060Y1005007D01*
X2255276Y1003852D01*
Y1002697D01*
X2255060Y1001542D01*
X2254627Y1000532D01*
X2253977Y999666D01*
X2253219Y999088D01*
X2252353Y998944D01*
G01X2258849Y1007605D02*
Y998944D01*
X2263179D01*
G01X2267293D02*
Y1007605D01*
X2269458D01*
X2270325Y1007172D01*
X2270974Y1006595D01*
X2271516Y1005729D01*
X2271949Y1004718D01*
X2272057Y1003274D01*
X2271949Y1001831D01*
X2271516Y1000820D01*
X2270974Y999954D01*
X2270325Y999377D01*
X2269458Y998944D01*
X2267293D01*
G01X2280501D02*
X2276171D01*
Y1007605D01*
X2280501D01*
G01X2278769Y1003419D02*
X2276171D01*
G01X2284832Y998944D02*
Y1007605D01*
X2287538D01*
X2288404Y1007172D01*
X2288946Y1006595D01*
X2289162Y1005440D01*
X2288946Y1004285D01*
X2288296Y1003563D01*
X2287538Y1003130D01*
X2284832D01*
G01X2287538D02*
X2289162Y998944D01*
G01X2302045Y1000099D02*
X2302912Y999377D01*
X2303886Y998944D01*
X2304752D01*
X2305618Y999377D01*
X2306268Y1000099D01*
X2306593Y1001109D01*
X2306376Y1002120D01*
X2305835Y1002986D01*
X2304860Y1003563D01*
X2303561Y1003852D01*
X2302803Y1004429D01*
X2302478Y1005440D01*
X2302695Y1006450D01*
X2303236Y1007172D01*
X2303994Y1007605D01*
X2304752D01*
X2305510Y1007316D01*
X2306160Y1006595D01*
G01X2311681Y1007605D02*
X2314279D01*
G01X2312980D02*
Y998944D01*
G01X2311681D02*
X2314279D01*
G01X2319259D02*
Y1007605D01*
X2321424D01*
X2322291Y1007172D01*
X2322940Y1006595D01*
X2323482Y1005729D01*
X2323915Y1004718D01*
X2324023Y1003274D01*
X2323915Y1001831D01*
X2323482Y1000820D01*
X2322940Y999954D01*
X2322291Y999377D01*
X2321424Y998944D01*
X2319259D01*
G01X2332467D02*
X2328137D01*
Y1007605D01*
X2332467D01*
G01X2330735Y1003419D02*
X2328137D01*
G01X2053800Y990282D02*
X2055965D01*
Y987684D01*
X2055315Y986818D01*
X2054557Y986241D01*
X2053475Y985952D01*
X2052392Y986241D01*
X2051634Y986818D01*
X2050985Y987684D01*
X2050551Y988695D01*
X2050335Y989849D01*
Y990860D01*
X2050551Y991726D01*
X2050985Y992737D01*
X2051634Y993603D01*
X2052284Y994180D01*
X2053150Y994613D01*
X2053908D01*
X2054774Y994324D01*
X2055424Y993747D01*
G01X2059321Y985952D02*
Y994613D01*
X2064301Y985952D01*
Y994613D01*
G01X2068090Y985952D02*
Y994613D01*
X2070255D01*
X2071122Y994180D01*
X2071771Y993603D01*
X2072313Y992737D01*
X2072746Y991726D01*
X2072854Y990282D01*
X2072746Y988839D01*
X2072313Y987828D01*
X2071771Y986962D01*
X2071122Y986385D01*
X2070255Y985952D01*
X2068090D01*
G01X2085087D02*
X2087794Y994613D01*
X2090501Y985952D01*
G01X2089526Y988983D02*
X2086062D01*
G01X2098837Y993891D02*
X2098187Y994324D01*
X2097429Y994613D01*
X2096563D01*
X2095589Y994180D01*
X2094831Y993458D01*
X2094290Y992592D01*
X2093856Y991149D01*
X2093748Y989849D01*
X2093965Y988550D01*
X2094290Y987684D01*
X2094939Y986818D01*
X2095697Y986241D01*
X2096455Y985952D01*
X2097213D01*
X2097971Y986241D01*
X2098620Y986674D01*
X2099162Y987251D01*
G01X2107498Y993891D02*
X2106848Y994324D01*
X2106090Y994613D01*
X2105224D01*
X2104250Y994180D01*
X2103492Y993458D01*
X2102951Y992592D01*
X2102517Y991149D01*
X2102409Y989849D01*
X2102626Y988550D01*
X2102951Y987684D01*
X2103600Y986818D01*
X2104358Y986241D01*
X2105116Y985952D01*
X2105874D01*
X2106632Y986241D01*
X2107281Y986674D01*
X2107823Y987251D01*
G01X2115942Y985952D02*
X2111612D01*
Y994613D01*
X2115942D01*
G01X2114210Y990427D02*
X2111612D01*
G01X2120273Y985952D02*
Y994613D01*
X2122871D01*
X2123737Y994180D01*
X2124387Y993170D01*
X2124603Y992015D01*
X2124387Y990860D01*
X2123845Y989994D01*
X2122871Y989561D01*
X2120273D01*
G01X2131099Y994613D02*
Y985952D01*
G01X2128609Y994613D02*
X2133589D01*
G01X2137053Y985952D02*
X2139760Y994613D01*
X2142467Y985952D01*
G01X2141492Y988983D02*
X2138028D01*
G01X2149287Y990571D02*
X2149720Y991004D01*
X2150045Y991726D01*
X2150262Y992737D01*
X2150045Y993603D01*
X2149612Y994180D01*
X2148854Y994613D01*
X2145931D01*
Y985952D01*
X2149504D01*
X2150262Y986529D01*
X2150695Y987395D01*
X2150911Y988406D01*
X2150695Y989416D01*
X2150045Y990282D01*
X2149287Y990571D01*
X2145931D01*
G01X2154917Y994613D02*
Y985952D01*
X2159247D01*
G01X2167908D02*
X2163578D01*
Y994613D01*
X2167908D01*
G01X2166176Y990427D02*
X2163578D01*
G01X2012936Y1381446D02*
X2520810D01*
G01X2077163Y-792523D02*
Y-776923D01*
X2074823Y-780043D01*
G01Y-792523D02*
X2079503D01*
G01X2095063D02*
Y-776923D01*
X2092723Y-780043D01*
G01Y-792523D02*
X2097403D01*
G01X2113698Y-717898D02*
X2118108Y-742898D01*
X2123148Y-717898D01*
X2128188Y-742898D01*
X2132598Y-717898D01*
G01X2148348Y-726232D02*
Y-742898D01*
G01Y-719565D02*
X2147718Y-719148D01*
Y-718315D01*
X2148348Y-717898D01*
X2148978Y-718315D01*
Y-719148D01*
X2148348Y-719565D01*
G01X2168823Y-739982D02*
X2170398Y-741648D01*
X2172603Y-742898D01*
X2174493D01*
X2176383Y-742065D01*
X2177643Y-740815D01*
X2178273Y-739149D01*
X2177958Y-736648D01*
X2176698Y-735398D01*
X2171028Y-732899D01*
X2169768Y-729981D01*
X2170398Y-727898D01*
X2171658Y-726648D01*
X2173548Y-726232D01*
X2175438Y-726648D01*
X2177328Y-727898D01*
G01X2198748Y-717898D02*
Y-742898D01*
G01X2194338Y-726232D02*
X2203158D01*
G01X2219538Y-742898D02*
Y-726232D01*
G01Y-729564D02*
X2221113Y-727898D01*
X2222688Y-726648D01*
X2224893Y-726232D01*
X2226468Y-726648D01*
X2228358Y-727898D01*
G01X2249148Y-742898D02*
X2247258Y-742481D01*
X2245368Y-740815D01*
X2244108Y-737898D01*
X2243478Y-734565D01*
X2244108Y-731232D01*
X2245368Y-728315D01*
X2247258Y-726648D01*
X2249148Y-726232D01*
X2251038Y-726648D01*
X2252928Y-728315D01*
X2254188Y-731232D01*
X2254503Y-734565D01*
X2254188Y-737898D01*
X2252928Y-740815D01*
X2251038Y-742481D01*
X2249148Y-742898D01*
G01X2268993D02*
Y-726232D01*
G01Y-730398D02*
X2270253Y-728315D01*
X2272143Y-726648D01*
X2274663Y-726232D01*
X2276868Y-726648D01*
X2278758Y-728315D01*
X2279703Y-731232D01*
Y-742898D01*
G01X2331678Y-719982D02*
X2329788Y-718731D01*
X2327583Y-717898D01*
X2325063D01*
X2322228Y-719148D01*
X2320023Y-721231D01*
X2318448Y-723732D01*
X2317188Y-727898D01*
X2316873Y-731648D01*
X2317503Y-735398D01*
X2318448Y-737898D01*
X2320338Y-740399D01*
X2322543Y-742065D01*
X2324748Y-742898D01*
X2326953D01*
X2329158Y-742065D01*
X2331048Y-740815D01*
X2332623Y-739149D01*
G01X2349948Y-742898D02*
X2348058Y-742481D01*
X2346168Y-740815D01*
X2344908Y-737898D01*
X2344278Y-734565D01*
X2344908Y-731232D01*
X2346168Y-728315D01*
X2348058Y-726648D01*
X2349948Y-726232D01*
X2351838Y-726648D01*
X2353728Y-728315D01*
X2354988Y-731232D01*
X2355303Y-734565D01*
X2354988Y-737898D01*
X2353728Y-740815D01*
X2351838Y-742481D01*
X2349948Y-742898D01*
G01X2370738D02*
Y-726232D01*
G01Y-729564D02*
X2372313Y-727898D01*
X2373888Y-726648D01*
X2376093Y-726232D01*
X2377668Y-726648D01*
X2379558Y-727898D01*
G01X2394678Y-751231D02*
Y-726232D01*
G01Y-729981D02*
X2396253Y-727898D01*
X2397828Y-726648D01*
X2400348Y-726232D01*
X2402553Y-726648D01*
X2404758Y-728731D01*
X2405703Y-731648D01*
X2406018Y-734565D01*
X2405703Y-737482D01*
X2404758Y-740399D01*
X2402868Y-742065D01*
X2400348Y-742898D01*
X2398143Y-742481D01*
X2395938Y-741232D01*
X2394678Y-739565D01*
G01X2425548Y-742898D02*
X2423658Y-742481D01*
X2421768Y-740815D01*
X2420508Y-737898D01*
X2419878Y-734565D01*
X2420508Y-731232D01*
X2421768Y-728315D01*
X2423658Y-726648D01*
X2425548Y-726232D01*
X2427438Y-726648D01*
X2429328Y-728315D01*
X2430588Y-731232D01*
X2430903Y-734565D01*
X2430588Y-737898D01*
X2429328Y-740815D01*
X2427438Y-742481D01*
X2425548Y-742898D01*
G01X2446338D02*
Y-726232D01*
G01Y-729564D02*
X2447913Y-727898D01*
X2449488Y-726648D01*
X2451693Y-726232D01*
X2453268Y-726648D01*
X2455158Y-727898D01*
G01X2481618Y-742898D02*
Y-726232D01*
G01Y-729148D02*
X2480358Y-727482D01*
X2478468Y-726648D01*
X2476263Y-726232D01*
X2474058Y-727065D01*
X2472168Y-728731D01*
X2470908Y-731232D01*
X2470278Y-734565D01*
X2470908Y-737898D01*
X2472168Y-740399D01*
X2474058Y-742065D01*
X2476263Y-742898D01*
X2478468Y-742481D01*
X2480358Y-741232D01*
X2481618Y-739565D01*
G01X2501148Y-717898D02*
Y-742898D01*
G01X2496738Y-726232D02*
X2505558D01*
G01X2526348D02*
Y-742898D01*
G01Y-719565D02*
X2525718Y-719148D01*
Y-718315D01*
X2526348Y-717898D01*
X2526978Y-718315D01*
Y-719148D01*
X2526348Y-719565D01*
G01X2551548Y-742898D02*
X2549658Y-742481D01*
X2547768Y-740815D01*
X2546508Y-737898D01*
X2545878Y-734565D01*
X2546508Y-731232D01*
X2547768Y-728315D01*
X2549658Y-726648D01*
X2551548Y-726232D01*
X2553438Y-726648D01*
X2555328Y-728315D01*
X2556588Y-731232D01*
X2556903Y-734565D01*
X2556588Y-737898D01*
X2555328Y-740815D01*
X2553438Y-742481D01*
X2551548Y-742898D01*
G01X2571393D02*
Y-726232D01*
G01Y-730398D02*
X2572653Y-728315D01*
X2574543Y-726648D01*
X2577063Y-726232D01*
X2579268Y-726648D01*
X2581158Y-728315D01*
X2582103Y-731232D01*
Y-742898D01*
G01X2077163Y1385233D02*
Y1400833D01*
X2074823Y1397713D01*
G01Y1385233D02*
X2079503D01*
G01X2095063D02*
Y1400833D01*
X2092723Y1397713D01*
G01Y1385233D02*
X2097403D01*
G01X2185882Y-777373D02*
Y-796310D01*
G01X2201084Y-777373D02*
X2851519D01*
G01X2220362Y-693460D02*
Y-497938D01*
G01X2186828Y1400383D02*
Y1381446D01*
G01X2294938Y-792523D02*
Y-776923D01*
X2292598Y-780043D01*
G01Y-792523D02*
X2297278D01*
G01X2309133Y-779523D02*
X2310303Y-777963D01*
X2311668Y-777183D01*
X2313228Y-776923D01*
X2315178Y-777443D01*
X2316543Y-778743D01*
X2316933Y-780303D01*
X2316738Y-781863D01*
X2315958Y-783163D01*
X2312058Y-785763D01*
X2310303Y-787583D01*
X2309133Y-790183D01*
X2308743Y-792523D01*
X2316933D01*
G01X2244739Y-640125D02*
Y-620125D01*
X2241739Y-624125D01*
G01Y-640125D02*
X2247739D01*
G01X2258489D02*
X2264739Y-620125D01*
X2270989Y-640125D01*
G01X2268739Y-633125D02*
X2260739D01*
G01X2242915Y-593064D02*
Y-573064D01*
X2239915Y-577064D01*
G01Y-593064D02*
X2245915D01*
G01X2265915D02*
Y-573064D01*
X2256665Y-587397D01*
X2269165D01*
G01X2278165Y-584731D02*
X2279915Y-582397D01*
X2281415Y-581064D01*
X2283415Y-580398D01*
X2285165Y-581064D01*
X2286415Y-582397D01*
X2287415Y-584397D01*
X2287665Y-586731D01*
X2287415Y-588731D01*
X2286415Y-590731D01*
X2284915Y-592397D01*
X2283165Y-593064D01*
X2281165Y-592397D01*
X2279415Y-590398D01*
X2278415Y-587397D01*
X2278165Y-584064D01*
X2278665Y-579731D01*
X2279415Y-577397D01*
X2280665Y-575064D01*
X2282415Y-573397D01*
X2284165Y-573064D01*
X2285915Y-573731D01*
X2287165Y-575397D01*
G01X2298165Y-576397D02*
X2299665Y-574398D01*
X2301415Y-573397D01*
X2303415Y-573064D01*
X2305915Y-573731D01*
X2307665Y-575397D01*
X2308165Y-577397D01*
X2307915Y-579398D01*
X2306915Y-581064D01*
X2301915Y-584397D01*
X2299665Y-586731D01*
X2298165Y-590065D01*
X2297665Y-593064D01*
X2308165D01*
G01X2318665Y-590731D02*
X2320415Y-592397D01*
X2322415Y-593064D01*
X2324415Y-592397D01*
X2326165Y-590398D01*
X2327415Y-587397D01*
X2327915Y-584397D01*
Y-580731D01*
X2327415Y-577731D01*
X2326165Y-575064D01*
X2324665Y-573731D01*
X2322915Y-573064D01*
X2320915Y-573731D01*
X2319415Y-575064D01*
X2318415Y-577064D01*
X2317915Y-579731D01*
X2318415Y-582064D01*
X2319665Y-584397D01*
X2321165Y-585731D01*
X2322915Y-586064D01*
X2324915Y-585398D01*
X2326415Y-583731D01*
X2327915Y-580731D01*
G01X2244196Y-539512D02*
Y-519512D01*
G01X2254696D02*
Y-539512D01*
G01Y-529512D02*
X2244196D01*
G01X2269446Y-539512D02*
X2267446Y-539179D01*
X2265696Y-537846D01*
X2264196Y-535846D01*
X2263196Y-533512D01*
X2262696Y-530845D01*
Y-528179D01*
X2263196Y-525512D01*
X2264196Y-523178D01*
X2265696Y-521179D01*
X2267446Y-519845D01*
X2269446Y-519512D01*
X2271446Y-519845D01*
X2273196Y-521179D01*
X2274696Y-523178D01*
X2275696Y-525512D01*
X2276196Y-528179D01*
Y-530845D01*
X2275696Y-533512D01*
X2274696Y-535846D01*
X2273196Y-537846D01*
X2271446Y-539179D01*
X2269446Y-539512D01*
G01X2283696D02*
Y-519512D01*
X2295196Y-539512D01*
Y-519512D01*
G01X2314446Y-539512D02*
X2304446D01*
Y-519512D01*
X2314446D01*
G01X2310446Y-529178D02*
X2304446D01*
G01X2329446Y-539512D02*
Y-530512D01*
X2324446Y-519512D01*
G01X2334446D02*
X2329446Y-530512D01*
G01X2371446Y-528845D02*
X2372446Y-527845D01*
X2373196Y-526179D01*
X2373696Y-523845D01*
X2373196Y-521845D01*
X2372196Y-520512D01*
X2370446Y-519512D01*
X2363696D01*
Y-539512D01*
X2371946D01*
X2373696Y-538179D01*
X2374696Y-536179D01*
X2375196Y-533845D01*
X2374696Y-531512D01*
X2373196Y-529512D01*
X2371446Y-528845D01*
X2363696D01*
G01X2383196Y-539512D02*
X2389446Y-519512D01*
X2395696Y-539512D01*
G01X2393446Y-532512D02*
X2385446D01*
G01X2403946Y-539512D02*
Y-519512D01*
X2408946D01*
X2410946Y-520512D01*
X2412446Y-521845D01*
X2413696Y-523845D01*
X2414696Y-526179D01*
X2414946Y-529512D01*
X2414696Y-532846D01*
X2413696Y-535179D01*
X2412446Y-537179D01*
X2410946Y-538512D01*
X2408946Y-539512D01*
X2403946D01*
G01X2430946Y-529512D02*
X2435946D01*
Y-535512D01*
X2434446Y-537512D01*
X2432696Y-538845D01*
X2430196Y-539512D01*
X2427696Y-538845D01*
X2425946Y-537512D01*
X2424446Y-535512D01*
X2423446Y-533179D01*
X2422946Y-530512D01*
Y-528179D01*
X2423446Y-526179D01*
X2424446Y-523845D01*
X2425946Y-521845D01*
X2427446Y-520512D01*
X2429446Y-519512D01*
X2431196D01*
X2433196Y-520179D01*
X2434696Y-521512D01*
G01X2454446Y-539512D02*
X2444446D01*
Y-519512D01*
X2454446D01*
G01X2450446Y-529178D02*
X2444446D01*
G01X2464446Y-539512D02*
Y-519512D01*
X2470696D01*
X2472696Y-520512D01*
X2473946Y-521845D01*
X2474446Y-524512D01*
X2473946Y-527179D01*
X2472446Y-528845D01*
X2470696Y-529846D01*
X2464446D01*
G01X2470696D02*
X2474446Y-539512D01*
G01X2504446D02*
Y-519512D01*
X2510446D01*
X2512446Y-520512D01*
X2513946Y-522845D01*
X2514446Y-525512D01*
X2513946Y-528179D01*
X2512696Y-530179D01*
X2510446Y-531179D01*
X2504446D01*
G01X2529446Y-519512D02*
Y-539512D01*
G01X2523696Y-519512D02*
X2535196D01*
G01X2551446Y-528845D02*
X2552446Y-527845D01*
X2553196Y-526179D01*
X2553696Y-523845D01*
X2553196Y-521845D01*
X2552196Y-520512D01*
X2550446Y-519512D01*
X2543696D01*
Y-539512D01*
X2551946D01*
X2553696Y-538179D01*
X2554696Y-536179D01*
X2555196Y-533845D01*
X2554696Y-531512D01*
X2553196Y-529512D01*
X2551446Y-528845D01*
X2543696D01*
G01X2348321Y501676D02*
X2276535Y414502D01*
G01X2276378Y417717D02*
X2269692Y423222D01*
X2271413Y425312D01*
X2272298Y425705D01*
X2273088Y425756D01*
X2274117Y425189D01*
X2274871Y424288D01*
X2275015Y423328D01*
X2274867Y422467D01*
X2273147Y420378D01*
G01X2274867Y422467D02*
X2279131Y421060D01*
G01X2281885Y424404D02*
X2275199Y429910D01*
X2277444Y422872D01*
X2280885Y427051D01*
G01X2286787Y429904D02*
X2286538Y429828D01*
X2286316Y430012D01*
X2286342Y430271D01*
X2286591Y430346D01*
X2286814Y430163D01*
X2286787Y429904D01*
G01X2289554Y435760D02*
X2290524Y435803D01*
X2291340Y436113D01*
X2292071Y436773D01*
X2292467Y437709D01*
X2292503Y438661D01*
X2292068Y439721D01*
X2291245Y440539D01*
X2290216Y441106D01*
X2289314Y441147D01*
X2288387Y440929D01*
X2287794Y440436D01*
X2287424Y439759D01*
X2287250Y438640D01*
X2284559Y441276D01*
X2286417Y443533D01*
G01X2290891Y448965D02*
X2290563Y448113D01*
X2290707Y447153D01*
X2291100Y446268D01*
X2291786Y445283D01*
X2292720Y444373D01*
X2293791Y443631D01*
X2294889Y443148D01*
X2295833Y442931D01*
X2296803Y442974D01*
X2297577Y443459D01*
X2297904Y444311D01*
X2297760Y445272D01*
X2297367Y446157D01*
X2296682Y447141D01*
X2295748Y448051D01*
X2294676Y448793D01*
X2293578Y449277D01*
X2292634Y449493D01*
X2291664Y449450D01*
X2290891Y448965D01*
G01X2265317Y1385233D02*
Y1400833D01*
X2262977Y1397713D01*
G01Y1385233D02*
X2267657D01*
G01X2279512Y1398233D02*
X2280682Y1399793D01*
X2282047Y1400573D01*
X2283607Y1400833D01*
X2285557Y1400313D01*
X2286922Y1399013D01*
X2287312Y1397453D01*
X2287117Y1395893D01*
X2286337Y1394593D01*
X2282437Y1391993D01*
X2280682Y1390173D01*
X2279512Y1387573D01*
X2279122Y1385233D01*
X2287312D01*
G01X2359583Y533069D02*
G03Y497635I0J-17717D01*
G01X2415925Y-260869D02*
G03I-17716J0D01*
G01X2406083D02*
G03I-7874J0D01*
G01X2435610Y164328D02*
G03I-17716J0D01*
G01X2406827Y497635D02*
X2359583D01*
G01X2406827Y533069D02*
X2359583D01*
G01X2414701Y515352D02*
G03I-7874J0D01*
G01X2426512Y922832D02*
X2379268D01*
G01X2426512Y958265D02*
X2379268D01*
G01D02*
G03Y922832I0J-17716D01*
G01X2376878Y1400383D02*
Y1381446D01*
G01X2406499Y-777373D02*
Y-796310D01*
G01X2409487Y-603015D02*
Y-693145D01*
G01X2408387Y-648334D02*
X2822042D01*
G01X2462506Y-684395D02*
Y-664395D01*
X2467506D01*
X2469506Y-665395D01*
X2471006Y-666728D01*
X2472256Y-668728D01*
X2473256Y-671062D01*
X2473506Y-674395D01*
X2473256Y-677729D01*
X2472256Y-680062D01*
X2471006Y-682062D01*
X2469506Y-683395D01*
X2467506Y-684395D01*
X2462506D01*
G01X2492506D02*
Y-671062D01*
G01Y-673395D02*
X2491506Y-672062D01*
X2490006Y-671395D01*
X2488256Y-671062D01*
X2486506Y-671729D01*
X2485006Y-673062D01*
X2484006Y-675062D01*
X2483506Y-677729D01*
X2484006Y-680395D01*
X2485006Y-682395D01*
X2486506Y-683728D01*
X2488256Y-684395D01*
X2490006Y-684062D01*
X2491506Y-683062D01*
X2492506Y-681729D01*
G01X2508006Y-664395D02*
Y-684395D01*
G01X2504506Y-671062D02*
X2511506D01*
G01X2524256Y-675395D02*
X2532256D01*
X2531506Y-673062D01*
X2530256Y-671729D01*
X2528506Y-671062D01*
X2526756Y-671395D01*
X2525256Y-672395D01*
X2524256Y-674729D01*
X2523756Y-676729D01*
Y-678728D01*
X2524256Y-680729D01*
X2525506Y-682729D01*
X2527006Y-684062D01*
X2528756Y-684395D01*
X2530506Y-683728D01*
X2532256Y-681729D01*
G01X2425433Y-615687D02*
Y-635687D01*
G01X2419683Y-615687D02*
X2431183D01*
G01X2441183Y-635687D02*
Y-615687D01*
G01Y-625353D02*
X2442433Y-623687D01*
X2443683Y-622687D01*
X2445683Y-622354D01*
X2447183Y-622687D01*
X2448933Y-624020D01*
X2449683Y-626021D01*
Y-635687D01*
G01X2465433Y-622354D02*
Y-635687D01*
G01Y-617021D02*
X2464933Y-616687D01*
Y-616020D01*
X2465433Y-615687D01*
X2465933Y-616020D01*
Y-616687D01*
X2465433Y-617021D01*
G01X2489433Y-624020D02*
X2487683Y-622687D01*
X2486183Y-622354D01*
X2484183Y-623021D01*
X2482683Y-624354D01*
X2481683Y-626687D01*
X2481433Y-629021D01*
X2481683Y-631354D01*
X2482683Y-633354D01*
X2484183Y-635020D01*
X2486183Y-635687D01*
X2487933Y-635020D01*
X2489433Y-633687D01*
G01X2501183Y-635687D02*
Y-615687D01*
G01X2509183Y-622354D02*
X2501183Y-630020D01*
G01X2504433Y-627020D02*
X2509683Y-635687D01*
G01X2521183D02*
Y-622354D01*
G01Y-625687D02*
X2522183Y-624020D01*
X2523683Y-622687D01*
X2525683Y-622354D01*
X2527433Y-622687D01*
X2528933Y-624020D01*
X2529683Y-626354D01*
Y-635687D01*
G01X2541683Y-626687D02*
X2549683D01*
X2548933Y-624354D01*
X2547683Y-623021D01*
X2545933Y-622354D01*
X2544183Y-622687D01*
X2542683Y-623687D01*
X2541683Y-626021D01*
X2541183Y-628021D01*
Y-630020D01*
X2541683Y-632021D01*
X2542933Y-634021D01*
X2544433Y-635354D01*
X2546183Y-635687D01*
X2547933Y-635020D01*
X2549683Y-633021D01*
G01X2561683Y-633354D02*
X2562933Y-634687D01*
X2564683Y-635687D01*
X2566183D01*
X2567683Y-635020D01*
X2568683Y-634021D01*
X2569183Y-632688D01*
X2568933Y-630687D01*
X2567933Y-629687D01*
X2563433Y-627687D01*
X2562433Y-625353D01*
X2562933Y-623687D01*
X2563933Y-622687D01*
X2565433Y-622354D01*
X2566933Y-622687D01*
X2568433Y-623687D01*
G01X2581683Y-633354D02*
X2582933Y-634687D01*
X2584683Y-635687D01*
X2586183D01*
X2587683Y-635020D01*
X2588683Y-634021D01*
X2589183Y-632688D01*
X2588933Y-630687D01*
X2587933Y-629687D01*
X2583433Y-627687D01*
X2582433Y-625353D01*
X2582933Y-623687D01*
X2583933Y-622687D01*
X2585433Y-622354D01*
X2586933Y-622687D01*
X2588433Y-623687D01*
G01X2526938Y69250D02*
X2445453D01*
G01X2526938Y94053D02*
X2445453D01*
G01X2441516Y73187D02*
Y90116D01*
G01Y73187D02*
G03X2445453Y69250I3937J0D01*
G01Y94053D02*
G03X2441516Y90116I0J-3937D01*
G01X2425768Y164328D02*
G03I-7874J0D01*
G01X2423641Y169710D02*
X2495000Y236530D01*
G01X2406827Y497635D02*
G03Y533069I0J17717D01*
G01X2535556Y845470D02*
X2454071D01*
G01X2450134Y849407D02*
G03X2454071Y845470I3937J0D01*
G01X2535556Y870273D02*
X2454071D01*
G01X2450134Y849407D02*
Y866336D01*
G01X2454071Y870273D02*
G03X2450134Y866336I0J-3937D01*
G01Y870273D02*
Y1015987D01*
G01X2426512Y922832D02*
G03Y958265I0J17717D01*
G01X2434386Y940549D02*
G03I-7874J0D01*
G01X2412350Y964579D02*
X2544587Y1068207D01*
G01X2447969Y1023565D02*
X2439308D01*
X2441040Y1022266D01*
G01X2447969D02*
Y1024864D01*
G01X2446237Y1029844D02*
X2447247Y1030494D01*
X2447825Y1031360D01*
X2447969Y1032334D01*
X2447825Y1033200D01*
X2447103Y1034067D01*
X2446237Y1034608D01*
X2445371Y1034716D01*
X2444360Y1034500D01*
X2443639Y1033742D01*
X2443350Y1032984D01*
Y1032009D01*
G01Y1032984D02*
X2442917Y1033633D01*
X2442195Y1034175D01*
X2441329Y1034391D01*
X2440463Y1034175D01*
X2439741Y1033633D01*
X2439308Y1032659D01*
X2439452Y1031685D01*
X2440030Y1030710D01*
G01X2447969Y1040670D02*
X2446093Y1040887D01*
X2444505Y1041212D01*
X2443061Y1041645D01*
X2441473Y1042186D01*
X2439308Y1043052D01*
Y1038722D01*
G01X2448258Y1049548D02*
X2448113Y1049331D01*
X2447825D01*
X2447680Y1049548D01*
X2447825Y1049765D01*
X2448113D01*
X2448258Y1049548D01*
G01X2444360Y1056152D02*
X2443350Y1056910D01*
X2442772Y1057559D01*
X2442484Y1058426D01*
X2442772Y1059183D01*
X2443350Y1059725D01*
X2444216Y1060158D01*
X2445226Y1060266D01*
X2446093Y1060158D01*
X2446959Y1059725D01*
X2447680Y1059075D01*
X2447969Y1058317D01*
X2447680Y1057451D01*
X2446814Y1056693D01*
X2445515Y1056260D01*
X2444072Y1056152D01*
X2442195Y1056368D01*
X2441184Y1056693D01*
X2440174Y1057235D01*
X2439452Y1057992D01*
X2439308Y1058750D01*
X2439597Y1059508D01*
X2440318Y1060050D01*
G01X2444360Y1064813D02*
X2443350Y1065571D01*
X2442772Y1066220D01*
X2442484Y1067087D01*
X2442772Y1067844D01*
X2443350Y1068386D01*
X2444216Y1068819D01*
X2445226Y1068927D01*
X2446093Y1068819D01*
X2446959Y1068386D01*
X2447680Y1067736D01*
X2447969Y1066978D01*
X2447680Y1066112D01*
X2446814Y1065354D01*
X2445515Y1064921D01*
X2444072Y1064813D01*
X2442195Y1065029D01*
X2441184Y1065354D01*
X2440174Y1065896D01*
X2439452Y1066653D01*
X2439308Y1067411D01*
X2439597Y1068169D01*
X2440318Y1068711D01*
G01X2514608Y-792523D02*
Y-776923D01*
X2512268Y-780043D01*
G01Y-792523D02*
X2516948D01*
G01X2528218Y-789403D02*
X2529388Y-791223D01*
X2530948Y-792263D01*
X2532703Y-792523D01*
X2534263Y-792263D01*
X2535823Y-790963D01*
X2536798Y-789403D01*
X2536993Y-787843D01*
X2536603Y-786023D01*
X2535238Y-784723D01*
X2533873Y-784203D01*
X2532118D01*
G01X2533873D02*
X2535043Y-783423D01*
X2536018Y-782123D01*
X2536408Y-780563D01*
X2536018Y-779003D01*
X2535043Y-777703D01*
X2533288Y-776923D01*
X2531533Y-777183D01*
X2529778Y-778223D01*
G01X2508150Y-147581D02*
G03I-7894J0D01*
G01Y27419D02*
G03I-7894J0D01*
G01X2495000Y236530D02*
X2498150D01*
G01D02*
X2604974D01*
G01X2508002Y245913D02*
X2508652Y246778D01*
X2509409Y247212D01*
X2510276Y247356D01*
X2511358Y247067D01*
X2512116Y246346D01*
X2512333Y245480D01*
X2512224Y244613D01*
X2511791Y243892D01*
X2509626Y242448D01*
X2508652Y241438D01*
X2508002Y239994D01*
X2507785Y238695D01*
X2512333D01*
G01X2516446D02*
X2520994Y247356D01*
G01X2516446D02*
X2520994Y238695D01*
G01X2548559Y542320D02*
X2475725D01*
G01D02*
Y845470D01*
G01X2528874Y612143D02*
X2462890D01*
G01X2530874Y613639D02*
X2481574D01*
G01X2462890Y612143D02*
Y820135D01*
G01X2476374Y618839D02*
G03X2481574Y613639I5200J0D01*
G01X2476374Y642139D02*
X2530874D01*
G01X2511774Y646139D02*
X2476374D01*
G01Y648639D02*
X2511774D01*
G01X2517374Y650639D02*
X2476374D01*
G01X2514020Y652222D02*
X2511658D01*
G01X2511909Y652517D02*
X2512663D01*
G01X2512965D02*
X2514020D01*
G01X2476374Y652639D02*
X2536874D01*
G01X2477624Y652789D02*
X2480124D01*
G01X2487624D02*
X2490124D01*
G01X2497624D02*
X2500124D01*
G01X2507624D02*
X2510124D01*
G01X2512361Y653748D02*
X2512211D01*
G01Y654043D02*
X2512412D01*
G01Y654437D02*
X2512010D01*
G01X2536874Y654449D02*
X2517374D01*
G01X2510124Y654489D02*
X2507624D01*
G01X2500124D02*
X2497624D01*
G01X2490124D02*
X2487624D01*
G01X2480124D02*
X2477624D01*
G01X2496874Y654639D02*
X2476374D01*
G01X2514020Y654732D02*
X2512060D01*
G01X2511658Y655027D02*
X2514020D01*
G01X2476374Y662639D02*
X2496874D01*
G01X2477624Y662789D02*
X2480124D01*
G01X2487624D02*
X2490124D01*
G01X2497624D02*
X2500124D01*
G01X2507624D02*
X2510124D01*
G01X2536874Y662829D02*
X2517374D01*
G01X2510124Y664489D02*
X2507624D01*
G01X2500124D02*
X2497624D01*
G01X2490124D02*
X2487624D01*
G01X2480124D02*
X2477624D01*
G01X2476374Y664639D02*
X2536874D01*
G01X2517374Y666639D02*
X2476374D01*
G01X2517374Y670639D02*
X2476374D01*
G01Y672639D02*
X2536874D01*
G01X2477624Y672789D02*
X2480124D01*
G01X2487624D02*
X2490124D01*
G01X2497624D02*
X2500124D01*
G01X2507624D02*
X2510124D01*
G01X2512512Y653698D02*
X2512361Y653748D01*
G01X2512412Y654043D02*
X2512563Y653994D01*
G01D02*
X2512764Y653846D01*
G01X2512010Y654437D02*
X2511658Y654732D01*
G01X2512060D02*
X2512412Y654437D01*
G01X2512060Y653994D02*
X2512211Y654043D01*
G01Y653748D02*
X2512060Y653698D01*
G01X2512613Y653600D02*
X2512512Y653698D01*
G01X2512764Y653846D02*
X2512915Y653649D01*
G01X2511859Y653846D02*
X2512060Y653994D01*
G01X2512663Y653452D02*
X2512613Y653600D01*
G01X2476374Y674639D02*
Y662639D01*
G01Y618839D02*
Y654639D01*
G01X2477624Y674489D02*
Y672789D01*
G01Y664489D02*
Y662789D01*
G01Y654489D02*
Y652789D01*
G01X2480124D02*
Y654489D01*
G01Y662789D02*
Y664489D01*
G01Y672789D02*
Y674489D01*
G01X2487624D02*
Y672789D01*
G01Y664489D02*
Y662789D01*
G01Y654489D02*
Y652789D01*
G01X2490124D02*
Y654489D01*
G01Y662789D02*
Y664489D01*
G01Y672789D02*
Y674489D01*
G01X2496874Y662639D02*
Y654639D01*
G01X2497624Y674489D02*
Y672789D01*
G01Y664489D02*
Y662789D01*
G01Y654489D02*
Y652789D01*
G01X2500124D02*
Y654489D01*
G01Y662789D02*
Y664489D01*
G01Y672789D02*
Y674489D01*
G01X2511708Y653649D02*
X2511859Y653846D01*
G01X2512060Y653698D02*
X2511959Y653600D01*
G01X2512915Y653649D02*
X2512965Y653403D01*
G01X2507624Y674489D02*
Y672789D01*
G01Y664489D02*
Y662789D01*
G01Y654489D02*
Y652789D01*
G01X2510124D02*
Y654489D01*
G01Y662789D02*
Y664489D01*
G01Y672789D02*
Y674489D01*
G01X2511658Y652222D02*
Y653403D01*
G01Y654732D02*
Y655027D01*
G01X2511774Y648639D02*
Y646139D01*
G01X2511909Y653452D02*
Y652517D01*
G01X2512663D02*
Y653452D01*
G01X2512965Y653403D02*
Y652517D01*
G01X2514020Y655027D02*
Y654732D01*
G01Y652517D02*
Y652222D01*
G01X2517374Y650639D02*
Y666639D01*
G01Y670639D02*
Y686639D01*
G01X2511658Y653403D02*
X2511708Y653649D01*
G01X2511959Y653600D02*
X2511909Y653452D01*
G01X2480627Y662639D02*
G03X2477122I-1753J980D01*
G01X2477145Y654639D02*
G03X2480604I1729J-1020D01*
G01X2490627Y662639D02*
G03X2487122I-1752J980D01*
G01X2487145Y654639D02*
G03X2490604I1729J-1020D01*
G01X2477122Y662639D02*
G03X2480627I1752J980D01*
G01X2480604Y654639D02*
G03X2477145I-1730J-1020D01*
G01X2487122Y662639D02*
G03X2490627I1752J980D01*
G01X2490604Y654639D02*
G03X2487145I-1730J-1020D01*
G01X2477145Y674639D02*
G03X2480604I1729J-1020D01*
G01X2487145D02*
G03X2490604I1729J-1020D01*
G01X2516768Y628639D02*
G03I-7894J0D01*
G01X2516374D02*
G03I-7500J0D01*
G01X2500882Y663620D02*
G03I-2008J0D01*
G01Y653620D02*
G03I-2008J0D01*
G01X2510882Y663620D02*
G03I-2008J0D01*
G01Y653620D02*
G03I-2008J0D01*
G01X2500882Y673620D02*
G03I-2008J0D01*
G01X2510882D02*
G03I-2008J0D01*
G01X2536874Y674449D02*
X2517374D01*
G01X2510124Y674489D02*
X2507624D01*
G01X2500124D02*
X2497624D01*
G01X2490124D02*
X2487624D01*
G01X2480124D02*
X2477624D01*
G01X2496874Y674639D02*
X2476374D01*
G01Y682639D02*
X2496874D01*
G01X2477624Y682789D02*
X2480124D01*
G01X2487624D02*
X2490124D01*
G01X2497624D02*
X2500124D01*
G01X2507624D02*
X2510124D01*
G01X2536874Y682829D02*
X2517374D01*
G01X2510124Y684489D02*
X2507624D01*
G01X2500124D02*
X2497624D01*
G01X2490124D02*
X2487624D01*
G01X2480124D02*
X2477624D01*
G01X2476374Y684639D02*
X2536874D01*
G01X2517374Y686639D02*
X2476374D01*
G01Y688639D02*
X2511774D01*
G01X2518174Y691139D02*
X2496874D01*
G01X2476374D02*
X2496874D01*
G01X2477574Y694839D02*
X2496874D01*
G01D02*
X2518174D01*
G01X2477574Y697439D02*
X2496874D01*
G01D02*
X2518174D01*
G01X2477574Y704839D02*
X2496874D01*
G01D02*
X2518174D01*
G01X2477574Y707439D02*
X2496874D01*
G01D02*
X2518174D01*
G01X2477574Y714839D02*
X2496874D01*
G01D02*
X2518174D01*
G01X2477574Y717439D02*
X2496874D01*
G01D02*
X2518174D01*
G01X2477574Y724839D02*
X2496874D01*
G01D02*
X2518174D01*
G01X2477574Y727439D02*
X2496874D01*
G01D02*
X2518174D01*
G01X2476374Y691139D02*
Y682639D01*
G01X2477574Y727439D02*
Y724839D01*
G01Y717439D02*
Y714839D01*
G01Y707439D02*
Y704839D01*
G01Y697439D02*
Y694839D01*
G01X2477624Y684489D02*
Y682789D01*
G01X2480124D02*
Y684489D01*
G01X2480174Y694839D02*
Y697439D01*
G01Y704839D02*
Y707439D01*
G01Y714839D02*
Y717439D01*
G01Y724839D02*
Y727439D01*
G01X2487574D02*
Y724839D01*
G01Y717439D02*
Y714839D01*
G01Y707439D02*
Y704839D01*
G01Y697439D02*
Y694839D01*
G01X2487624Y684489D02*
Y682789D01*
G01X2490124D02*
Y684489D01*
G01X2490174Y694839D02*
Y697439D01*
G01Y704839D02*
Y707439D01*
G01Y714839D02*
Y717439D01*
G01Y724839D02*
Y727439D01*
G01X2496874Y741139D02*
Y691139D01*
G01Y682639D02*
Y674639D01*
G01X2497574Y727439D02*
Y724839D01*
G01Y717439D02*
Y714839D01*
G01Y707439D02*
Y704839D01*
G01Y697439D02*
Y694839D01*
G01X2497624Y684489D02*
Y682789D01*
G01X2500124D02*
Y684489D01*
G01X2500174Y694839D02*
Y697439D01*
G01Y704839D02*
Y707439D01*
G01Y714839D02*
Y717439D01*
G01Y724839D02*
Y727439D01*
G01X2507574D02*
Y724839D01*
G01Y717439D02*
Y714839D01*
G01Y707439D02*
Y704839D01*
G01Y697439D02*
Y694839D01*
G01X2507624Y684489D02*
Y682789D01*
G01X2510124D02*
Y684489D01*
G01X2510174Y694839D02*
Y697439D01*
G01Y704839D02*
Y707439D01*
G01Y714839D02*
Y717439D01*
G01Y724839D02*
Y727439D01*
G01X2511774Y691139D02*
Y688639D01*
G01X2518174Y741139D02*
Y691139D01*
G01X2480404Y694839D02*
G03Y697439I-1530J1300D01*
G01X2480627Y682639D02*
G03X2477122I-1753J980D01*
G01X2480404Y697439D02*
G03Y694839I-1530J-1300D01*
G01X2477122Y682639D02*
G03X2480627I1752J980D01*
G01X2480604Y674639D02*
G03X2477145I-1730J-1020D01*
G01X2480404Y724839D02*
G03Y727439I-1530J1300D01*
G01Y714839D02*
G03Y717439I-1530J1300D01*
G01Y704839D02*
G03Y707439I-1530J1300D01*
G01Y727439D02*
G03Y724839I-1530J-1300D01*
G01Y717439D02*
G03Y714839I-1530J-1300D01*
G01Y707439D02*
G03Y704839I-1530J-1300D01*
G01X2490404Y694839D02*
G03Y697439I-1530J1300D01*
G01X2487382Y697483D02*
G03X2487344Y694839I1492J-1344D01*
G01X2490627Y682639D02*
G03X2487122I-1752J980D01*
G01X2490404Y697439D02*
G03X2487382Y697483I-1530J-1300D01*
G01X2487344Y694839D02*
G03X2490404I1530J1300D01*
G01X2487122Y682639D02*
G03X2490627I1752J980D01*
G01X2490604Y674639D02*
G03X2487145I-1730J-1020D01*
G01X2490404Y724839D02*
G03Y727439I-1530J1300D01*
G01X2487382Y727483D02*
G03X2487344Y724839I1492J-1344D01*
G01X2490404Y714839D02*
G03Y717439I-1530J1300D01*
G01X2487382Y717483D02*
G03X2487344Y714839I1492J-1344D01*
G01X2490404Y704839D02*
G03Y707439I-1530J1300D01*
G01X2487382Y707483D02*
G03X2487344Y704839I1492J-1344D01*
G01X2490404Y727439D02*
G03X2487382Y727483I-1530J-1300D01*
G01X2487344Y724839D02*
G03X2490404I1530J1300D01*
G01Y717439D02*
G03X2487382Y717483I-1530J-1300D01*
G01X2487344Y714839D02*
G03X2490404I1530J1300D01*
G01Y707439D02*
G03X2487382Y707483I-1530J-1300D01*
G01X2487344Y704839D02*
G03X2490404I1530J1300D01*
G01X2500882Y696139D02*
G03I-2008J0D01*
G01Y683620D02*
G03I-2008J0D01*
G01Y726139D02*
G03I-2008J0D01*
G01Y716139D02*
G03I-2008J0D01*
G01Y706139D02*
G03I-2008J0D01*
G01X2510882Y683620D02*
G03I-2008J0D01*
G01Y696139D02*
G03I-2008J0D01*
G01Y726139D02*
G03I-2008J0D01*
G01Y716139D02*
G03I-2008J0D01*
G01Y706139D02*
G03I-2008J0D01*
G01X2477574Y734839D02*
X2496874D01*
G01D02*
X2518174D01*
G01X2477574Y737439D02*
X2496874D01*
G01D02*
X2518174D01*
G01Y741139D02*
X2496874D01*
G01D02*
X2476374D01*
G01X2511774Y743639D02*
X2476374D01*
G01X2517374Y745639D02*
X2476374D01*
G01Y747639D02*
X2536874D01*
G01X2477624Y747789D02*
X2480124D01*
G01X2487624D02*
X2490124D01*
G01X2497624D02*
X2500124D01*
G01X2507624D02*
X2510124D01*
G01X2536874Y749449D02*
X2517374D01*
G01X2510124Y749489D02*
X2507624D01*
G01X2500124D02*
X2497624D01*
G01X2490124D02*
X2487624D01*
G01X2480124D02*
X2477624D01*
G01X2496874Y749639D02*
X2476374D01*
G01Y757639D02*
X2496874D01*
G01X2477624Y757789D02*
X2480124D01*
G01X2487624D02*
X2490124D01*
G01X2497624D02*
X2500124D01*
G01X2507624D02*
X2510124D01*
G01X2536874Y757829D02*
X2517374D01*
G01X2510124Y759489D02*
X2507624D01*
G01X2500124D02*
X2497624D01*
G01X2490124D02*
X2487624D01*
G01X2480124D02*
X2477624D01*
G01X2476374Y759639D02*
X2536874D01*
G01X2517374Y761639D02*
X2476374D01*
G01X2517374Y765639D02*
X2476374D01*
G01Y767639D02*
X2536874D01*
G01X2477624Y767789D02*
X2480124D01*
G01X2487624D02*
X2490124D01*
G01X2497624D02*
X2500124D01*
G01X2507624D02*
X2510124D01*
G01X2536874Y769449D02*
X2517374D01*
G01X2510124Y769489D02*
X2507624D01*
G01X2500124D02*
X2497624D01*
G01X2490124D02*
X2487624D01*
G01X2480124D02*
X2477624D01*
G01X2496874Y769639D02*
X2476374D01*
G01Y777639D02*
X2496874D01*
G01X2477624Y777789D02*
X2480124D01*
G01X2487624D02*
X2490124D01*
G01X2497624D02*
X2500124D01*
G01X2507624D02*
X2510124D01*
G01X2536874Y777829D02*
X2517374D01*
G01X2510124Y779489D02*
X2507624D01*
G01X2500124D02*
X2497624D01*
G01X2490124D02*
X2487624D01*
G01X2480124D02*
X2477624D01*
G01X2476374Y779639D02*
X2536874D01*
G01X2517374Y781639D02*
X2476374D01*
G01Y783639D02*
X2511774D01*
G01Y786139D02*
X2476374D01*
G01Y769639D02*
Y757639D01*
G01Y749639D02*
Y741139D01*
G01Y777639D02*
Y813439D01*
G01X2477574Y737439D02*
Y734839D01*
G01X2477624Y779489D02*
Y777789D01*
G01Y769489D02*
Y767789D01*
G01Y759489D02*
Y757789D01*
G01Y749489D02*
Y747789D01*
G01X2480124D02*
Y749489D01*
G01Y757789D02*
Y759489D01*
G01Y767789D02*
Y769489D01*
G01Y777789D02*
Y779489D01*
G01X2480174Y734839D02*
Y737439D01*
G01X2487574D02*
Y734839D01*
G01X2487624Y779489D02*
Y777789D01*
G01Y769489D02*
Y767789D01*
G01Y759489D02*
Y757789D01*
G01Y749489D02*
Y747789D01*
G01X2490124D02*
Y749489D01*
G01Y757789D02*
Y759489D01*
G01Y767789D02*
Y769489D01*
G01Y777789D02*
Y779489D01*
G01X2490174Y734839D02*
Y737439D01*
G01X2496874Y777639D02*
Y769639D01*
G01Y757639D02*
Y749639D01*
G01X2497574Y737439D02*
Y734839D01*
G01X2497624Y779489D02*
Y777789D01*
G01Y769489D02*
Y767789D01*
G01Y759489D02*
Y757789D01*
G01Y749489D02*
Y747789D01*
G01X2500124D02*
Y749489D01*
G01Y757789D02*
Y759489D01*
G01Y767789D02*
Y769489D01*
G01Y777789D02*
Y779489D01*
G01X2500174Y734839D02*
Y737439D01*
G01X2507574D02*
Y734839D01*
G01X2507624Y779489D02*
Y777789D01*
G01Y769489D02*
Y767789D01*
G01Y759489D02*
Y757789D01*
G01Y749489D02*
Y747789D01*
G01X2510124D02*
Y749489D01*
G01Y757789D02*
Y759489D01*
G01Y767789D02*
Y769489D01*
G01Y777789D02*
Y779489D01*
G01X2510174Y734839D02*
Y737439D01*
G01X2511774Y786139D02*
Y783639D01*
G01Y743639D02*
Y741139D01*
G01X2517374Y745639D02*
Y761639D01*
G01Y765639D02*
Y781639D01*
G01X2480404Y734839D02*
G03Y737439I-1530J1300D01*
G01X2490404Y734839D02*
G03Y737439I-1530J1300D01*
G01X2487382Y737483D02*
G03X2487344Y734839I1492J-1344D01*
G01X2477122Y749639D02*
G03X2480627I1752J-980D01*
G01X2487122D02*
G03X2490627I1752J-980D01*
G01X2480404Y737439D02*
G03Y734839I-1530J-1300D01*
G01X2490404Y737439D02*
G03X2487382Y737483I-1530J-1300D01*
G01X2487344Y734839D02*
G03X2490404I1530J1300D01*
G01X2480627Y749639D02*
G03X2477122I-1753J-980D01*
G01X2490627D02*
G03X2487122I-1752J-980D01*
G01X2480604Y777639D02*
G03X2477145I-1730J1020D01*
G01X2480604Y757639D02*
G03X2477145I-1730J1020D01*
G01X2477122Y769639D02*
G03X2480627I1752J-980D01*
G01X2490604Y777639D02*
G03X2487145I-1730J1020D01*
G01X2490604Y757639D02*
G03X2487145I-1730J1020D01*
G01X2487122Y769639D02*
G03X2490627I1752J-980D01*
G01X2477145Y777639D02*
G03X2480604I1729J1020D01*
G01X2477145Y757639D02*
G03X2480604I1729J1020D01*
G01X2480627Y769639D02*
G03X2477122I-1753J-980D01*
G01X2487145Y777639D02*
G03X2490604I1729J1020D01*
G01X2487145Y757639D02*
G03X2490604I1729J1020D01*
G01X2490627Y769639D02*
G03X2487122I-1752J-980D01*
G01X2500882Y748659D02*
G03I-2008J0D01*
G01X2510882D02*
G03I-2008J0D01*
G01X2500882Y736139D02*
G03I-2008J0D01*
G01X2510882D02*
G03I-2008J0D01*
G01X2500882Y768659D02*
G03I-2008J0D01*
G01X2510882Y778659D02*
G03I-2008J0D01*
G01Y758659D02*
G03I-2008J0D01*
G01Y768659D02*
G03I-2008J0D01*
G01X2500882Y778659D02*
G03I-2008J0D01*
G01Y758659D02*
G03I-2008J0D01*
G01X2530874Y790139D02*
X2476374D01*
G01X2530874Y818639D02*
X2481574D01*
G01X2462890Y820135D02*
X2528874D01*
G01X2509189Y825982D02*
X2532811D01*
G01X2528874Y829919D02*
X2513126D01*
G01X2513835Y841139D02*
X2518166D01*
G01X2513126Y844092D02*
X2528874D01*
G01X2509189Y848029D02*
Y825982D01*
G01X2513126Y829919D02*
Y844092D01*
G01X2513835Y829919D02*
Y841139D01*
G01X2518166D02*
Y829919D01*
G01X2516768Y803639D02*
G03I-7894J0D01*
G01X2516374D02*
G03I-7500J0D01*
G01X2481574Y818639D02*
G03X2476374Y813439I0J-5200D01*
G01X2532811Y848029D02*
X2509189D01*
G01Y869683D02*
X2532811D01*
G01X2528874Y873620D02*
X2513126D01*
G01X2513835Y884840D02*
X2518166D01*
G01X2513126Y887793D02*
X2528874D01*
G01X2532811Y891730D02*
X2509189D01*
G01X2475725Y893895D02*
X2548559D01*
G01X2475725D02*
Y870273D01*
G01X2509189Y891730D02*
Y869683D01*
G01X2513126Y873620D02*
Y887793D01*
G01X2513835Y873620D02*
Y884840D01*
G01X2518166D02*
Y873620D01*
G01X2491333Y921726D02*
X2491318Y921715D01*
G01X2492400Y927876D02*
X2492415Y927886D01*
G01X2505646Y921257D02*
X2502103Y919131D01*
G01X2477890Y923478D02*
X2486552Y930470D01*
G01X2488914Y928108D02*
X2485764Y924801D01*
G01X2493441Y921494D02*
X2491767Y919820D01*
G01D02*
X2491079Y919131D01*
G01X2497969Y928108D02*
X2495607Y925870D01*
G01D02*
X2493896Y924250D01*
G01X2491333Y921539D02*
X2491318Y921519D01*
G01X2492400Y928063D02*
X2492415Y928083D01*
G01X2488914Y924801D02*
X2490987Y928108D01*
G01X2495607Y920864D02*
X2505828Y922869D01*
G01X2494289Y919840D02*
X2494209Y919824D01*
G01X2494062Y919810D02*
X2494142Y919826D01*
G01X2494982Y920623D02*
X2494830Y920594D01*
G01X2494900Y921001D02*
X2494828Y920987D01*
G01X2478707Y919874D02*
X2478787Y919890D01*
G01X2494870Y928476D02*
X2494797Y928461D01*
G01X2494796Y928855D02*
X2494948Y928885D01*
G01X2494102Y929661D02*
X2494022Y929645D01*
G01X2475426Y932737D02*
X2476097Y934581D01*
G01X2476794Y929717D02*
X2476874Y929732D01*
G01X2494210Y919824D02*
X2494062Y919810D01*
G01X2494290Y919840D02*
X2494142Y919826D01*
G01X2484017Y916865D02*
X2483345Y915020D01*
G01X2495622Y932737D02*
X2496294Y934581D01*
G01X2514575Y915352D02*
X2514574D01*
G01X2510961Y914761D02*
X2468048D01*
G01Y917124D02*
X2510961D01*
G01X2504268Y917419D02*
X2502300D01*
G01X2481827D02*
X2479859D01*
G01X2511355Y917517D02*
X2510961D01*
G01X2470410D02*
X2510961D01*
G01X2513520Y917714D02*
X2510961D01*
G01X2468048D02*
X2465489D01*
G01X2468048Y917911D02*
X2465685D01*
G01X2470410D02*
X2511355D01*
G01X2482418Y918108D02*
X2506827D01*
G01X2513520Y918895D02*
X2512142D01*
G01X2469622D02*
X2468048D01*
G01X2489307D02*
X2493244D01*
G01X2502103Y919131D02*
X2493244D01*
G01D02*
X2489307D01*
G01X2477890D02*
X2489307D01*
G01X2520877Y919486D02*
X2519695D01*
G01X2517794D02*
X2516612D01*
G01X2519695D02*
X2517794D01*
G01X2516612D02*
X2514711D01*
G01D02*
X2506827D01*
G01X2478622Y919880D02*
X2476315D01*
G01X2499937Y920470D02*
X2483796D01*
G01X2497575Y920864D02*
X2501512D01*
G01X2468048Y921061D02*
X2465685D01*
G01X2509189Y921257D02*
X2505646D01*
G01X2483599Y921454D02*
X2500134D01*
G01X2497969Y921494D02*
X2495607D01*
G01D02*
X2493441D01*
G01X2488914D02*
X2490987D01*
G01X2499839Y921519D02*
X2492415D01*
G01X2491318D02*
X2483894D01*
G01Y921539D02*
X2491333D01*
G01X2492400D02*
X2499839D01*
G01Y921659D02*
X2492457D01*
G01X2491276D02*
X2483894D01*
G01X2499839Y921715D02*
X2492415D01*
G01X2491318D02*
X2483894D01*
G01Y921726D02*
X2491333D01*
G01X2492400D02*
X2499839D01*
G01Y921785D02*
X2492457D01*
G01X2491276D02*
X2483894D01*
G01X2499839Y922152D02*
X2483894D01*
G01X2483599Y922242D02*
X2500134D01*
G01X2499839Y922339D02*
X2483894D01*
G01X2468835Y922439D02*
X2471985D01*
G01X2511945D02*
X2512733D01*
G01X2483894Y922526D02*
X2499839D01*
G01X2515882Y922635D02*
X2499937D01*
G01X2483796D02*
X2477890D01*
G01X2517576Y923029D02*
X2516395D01*
G01X2518835D02*
X2517576D01*
G01X2516395D02*
X2514493D01*
G01D02*
X2501339D01*
G01D02*
X2499150D01*
G01X2483599D02*
X2499150D01*
G01X2499839Y923213D02*
X2492457D01*
G01X2491276D02*
X2483894D01*
G01X2483599Y923324D02*
X2500134D01*
G01X2498953Y923417D02*
X2493638D01*
G01X2490095D02*
X2484780D01*
G01X2499839Y923451D02*
X2492457D01*
G01X2491276D02*
X2483894D01*
G01Y923509D02*
X2491276D01*
G01X2492457D02*
X2499839D01*
G01Y923521D02*
X2492457D01*
G01X2491276D02*
X2483894D01*
G01X2498953Y923973D02*
X2493638D01*
G01X2490095D02*
X2484780D01*
G01X2503284Y924013D02*
X2495410D01*
G01X2493441D02*
X2485567D01*
G01X2483599D02*
X2475725D01*
G01X2495410Y924077D02*
X2493638D01*
G01X2485567D02*
X2484780D01*
G01X2495410Y924112D02*
X2493638D01*
G01X2485567D02*
X2484780D01*
G01X2493896Y924250D02*
X2495607D01*
G01D02*
X2497969D01*
G01X2495410Y924309D02*
X2493638D01*
G01X2485567D02*
X2484780D01*
G01X2465685Y924604D02*
X2468048D01*
G01X2465685Y924998D02*
X2468048D01*
G01X2495410Y925293D02*
X2493638D01*
G01X2485567D02*
X2484780D01*
G01X2495410Y925490D02*
X2493638D01*
G01X2485567D02*
X2484780D01*
G01X2495410Y925524D02*
X2493638D01*
G01X2485567D02*
X2484780D01*
G01X2503284Y925588D02*
X2495410D01*
G01X2493441D02*
X2485567D01*
G01X2483599D02*
X2475725D01*
G01X2498953Y925628D02*
X2493638D01*
G01X2490095D02*
X2484780D01*
G01X2499839Y926080D02*
X2492457D01*
G01X2491276D02*
X2483894D01*
G01X2499839Y926093D02*
X2492457D01*
G01X2491276D02*
X2483894D01*
G01Y926150D02*
X2491276D01*
G01X2492457D02*
X2499839D01*
G01X2498953Y926185D02*
X2493638D01*
G01X2490095D02*
X2484780D01*
G01X2483599Y926277D02*
X2500134D01*
G01X2499839Y926388D02*
X2492457D01*
G01X2491276D02*
X2483894D01*
G01X2499150Y926572D02*
X2483599D01*
G01X2499150D02*
X2501339D01*
G01D02*
X2514296D01*
G01D02*
X2516198D01*
G01D02*
X2517379D01*
G01D02*
X2518835D01*
G01X2477890Y926966D02*
X2483796D01*
G01X2499937D02*
X2515882D01*
G01X2499839Y927076D02*
X2483894D01*
G01X2512733Y927163D02*
X2511945D01*
G01X2471985D02*
X2468835D01*
G01X2483894Y927263D02*
X2499839D01*
G01X2483599Y927360D02*
X2500134D01*
G01X2483894Y927450D02*
X2499839D01*
G01X2483894Y927816D02*
X2491276D01*
G01X2492457D02*
X2499839D01*
G01Y927876D02*
X2492400D01*
G01X2491333D02*
X2483894D01*
G01X2499839Y927886D02*
X2492415D01*
G01X2491318D02*
X2483894D01*
G01Y927943D02*
X2491276D01*
G01X2492457D02*
X2499839D01*
G01Y928063D02*
X2492400D01*
G01X2491333D02*
X2483894D01*
G01X2499839Y928083D02*
X2492415D01*
G01X2491318D02*
X2483894D01*
G01X2490987Y928108D02*
X2488914D01*
G01X2483599Y928147D02*
X2500134D01*
G01X2509189Y928344D02*
X2505646D01*
G01X2501512Y928738D02*
X2497575D01*
G01X2483796Y929131D02*
X2499937D01*
G01X2478707Y919874D02*
X2489307Y919830D01*
G01X2493244Y919813D02*
X2494062Y919810D01*
G01X2489307Y919830D02*
X2493244Y919813D01*
G01X2494142Y919826D02*
X2493244Y919830D01*
G01D02*
X2489307Y919846D01*
G01D02*
X2478787Y919890D01*
G01X2494910Y920609D02*
X2494266Y920612D01*
G01X2494002Y920991D02*
X2494828Y920987D01*
G01X2494797Y928461D02*
X2493972Y928465D01*
G01X2504961Y916865D02*
X2504290Y915020D01*
G01X2476315Y929722D02*
X2476709D01*
G01X2506827Y930116D02*
X2514080D01*
G01D02*
X2515980D01*
G01D02*
X2517162D01*
G01D02*
X2519063D01*
G01D02*
X2520245D01*
G01X2502103Y930470D02*
X2493244D01*
G01D02*
X2489307D01*
G01X2477890D02*
X2479268D01*
G01X2484780D02*
X2489307D01*
G01X2493244Y930706D02*
X2489307D01*
G01X2468048D02*
X2469622D01*
G01X2512142D02*
X2513520D01*
G01X2482418Y931494D02*
X2506827D01*
G01X2470410Y931691D02*
X2511355D01*
G01X2465489Y931887D02*
X2468048D01*
G01X2510961D02*
X2513520D01*
G01X2470410Y932084D02*
X2510961D01*
G01D02*
X2511355D01*
G01X2479859Y932183D02*
X2481827D01*
G01X2502300D02*
X2504268D01*
G01X2510961Y932478D02*
X2468048D01*
G01Y934840D02*
X2510961D01*
G01X2519199Y934248D02*
X2519198D01*
G01X2494876Y928870D02*
X2494232Y928873D01*
G01X2494022Y929645D02*
X2476794Y929717D01*
G01X2476874Y929732D02*
X2489307Y929680D01*
G01D02*
X2493244Y929664D01*
G01D02*
X2494102Y929661D01*
G01X2465489Y917714D02*
Y931887D01*
G01X2465685Y924604D02*
Y917714D01*
G01D02*
Y917124D01*
G01Y924998D02*
Y931887D01*
G01D02*
Y932478D01*
G01X2468048Y914761D02*
Y917714D01*
G01D02*
Y924604D01*
G01Y924998D02*
Y931887D01*
G01D02*
Y934840D01*
G01X2468638Y917124D02*
Y932478D01*
G01X2470410Y917517D02*
Y918108D01*
G01Y931494D02*
Y932084D01*
G01X2472575Y934840D02*
Y932478D01*
G01Y914761D02*
Y917124D01*
G01X2475134Y914761D02*
Y917124D01*
G01Y932478D02*
Y934840D01*
G01X2505828Y926732D02*
X2495607Y928738D01*
G01X2493972Y928465D02*
X2494002Y920991D01*
G01X2494266Y920612D02*
X2494232Y928873D01*
G01X2494601Y920998D02*
X2494570Y928472D01*
G01X2494830Y920594D02*
X2494828Y920987D01*
G01X2494797Y928461D02*
X2494796Y928855D01*
G01X2494870Y928476D02*
X2494900Y921001D01*
G01X2494948Y928885D02*
X2494982Y920623D01*
G01X2475528Y932084D02*
Y930509D01*
G01Y919092D02*
Y917517D01*
G01X2475725Y925588D02*
Y924013D01*
G01X2475830Y925588D02*
Y924013D01*
G01X2477300Y925588D02*
Y924013D01*
G01X2477890Y919131D02*
Y930470D01*
G01X2478087Y924013D02*
Y925588D01*
G01X2478481D02*
Y924013D01*
G01X2479268Y919131D02*
Y918009D01*
G01Y930470D02*
Y931592D01*
G01X2480843Y925588D02*
Y924013D01*
G01X2481237Y925588D02*
Y924013D01*
G01X2482024Y925588D02*
Y924013D01*
G01X2482418Y918108D02*
Y918009D01*
G01Y931494D02*
Y931592D01*
G01X2483493Y925588D02*
Y924013D01*
G01X2483599Y928147D02*
Y921454D01*
G01X2483796Y920470D02*
Y922635D01*
G01Y926966D02*
Y929131D01*
G01X2483894Y921519D02*
Y928083D01*
G01X2484189Y917124D02*
Y914761D01*
G01Y932478D02*
Y934840D01*
G01X2484288Y926080D02*
Y925785D01*
G01Y923817D02*
Y923521D01*
G01X2484485Y926080D02*
Y925785D01*
G01Y923817D02*
Y923521D01*
G01X2484780Y926277D02*
Y925293D01*
G01Y924309D02*
Y923324D01*
G01Y919131D02*
Y918108D01*
G01Y930470D02*
Y931494D01*
G01X2485567Y925588D02*
Y924013D01*
G01X2485673Y925588D02*
Y924013D01*
G01X2486748Y931494D02*
Y930470D01*
G01Y918108D02*
Y919131D01*
G01X2487142Y925588D02*
Y924013D01*
G01X2487733Y917124D02*
Y914761D01*
G01Y932478D02*
Y934840D01*
G01X2487930Y924013D02*
Y925588D01*
G01X2488323D02*
Y924013D01*
G01X2489307Y930706D02*
Y918895D01*
G01X2490095Y926277D02*
Y925588D01*
G01Y924013D02*
Y923324D01*
G01X2490390Y923817D02*
Y923521D01*
G01Y925785D02*
Y926080D01*
G01X2490587Y923817D02*
Y923521D01*
G01Y925785D02*
Y926080D01*
G01X2490685Y924013D02*
Y925588D01*
G01X2491079D02*
Y924013D01*
G01X2491276Y927943D02*
Y926080D01*
G01Y923521D02*
Y921659D01*
G01X2491333Y921539D02*
Y921726D01*
G01Y927876D02*
Y928063D01*
G01X2491867Y925588D02*
Y924013D01*
G01Y917124D02*
Y914761D01*
G01Y932478D02*
Y934840D01*
G01X2492400Y921539D02*
Y921726D01*
G01Y927876D02*
Y928063D01*
G01X2492457Y921659D02*
Y923521D01*
G01Y926080D02*
Y927943D01*
G01X2493048Y931494D02*
Y930706D01*
G01D02*
Y930470D01*
G01Y918108D02*
Y918895D01*
G01D02*
Y919131D01*
G01X2493146Y926080D02*
Y925785D01*
G01Y923817D02*
Y923521D01*
G01X2493244Y918895D02*
Y930706D01*
G01X2493336Y925588D02*
Y924013D01*
G01X2493343Y926080D02*
Y925785D01*
G01Y923817D02*
Y923521D01*
G01X2493441Y925588D02*
Y924013D01*
G01X2493638Y924309D02*
Y923324D01*
G01Y926277D02*
Y925293D01*
G01X2495410Y925588D02*
Y924013D01*
G01Y917124D02*
Y914761D01*
G01Y932478D02*
Y934840D01*
G01X2495515Y925588D02*
Y924013D01*
G01X2495607Y928738D02*
Y920864D01*
G01X2496985Y925588D02*
Y924013D01*
G01X2497575Y917517D02*
Y920864D01*
G01Y928738D02*
Y932084D01*
G01X2497772Y924013D02*
Y925588D01*
G01X2497969Y930470D02*
Y928274D01*
G01D02*
Y928108D01*
G01Y924250D02*
Y921494D01*
G01X2498166Y925588D02*
Y924013D01*
G01X2498953Y926277D02*
Y925588D01*
G01Y924013D02*
Y923324D01*
G01X2499150Y923029D02*
Y926572D01*
G01X2499248Y923817D02*
Y923521D01*
G01Y925785D02*
Y926080D01*
G01X2499445Y923817D02*
Y923521D01*
G01Y925785D02*
Y926080D01*
G01X2499839Y921519D02*
Y928083D01*
G01X2499937Y929131D02*
Y926966D01*
G01Y922635D02*
Y920470D01*
G01X2500134Y921454D02*
Y928147D01*
G01X2500528Y924013D02*
Y925588D01*
G01X2500922D02*
Y924013D01*
G01X2501709Y925588D02*
Y924013D01*
G01Y918009D02*
Y918108D01*
G01Y931494D02*
Y931592D01*
G01X2503178Y925588D02*
Y924013D01*
G01X2503284Y925588D02*
Y924013D01*
G01X2510921Y932084D02*
X2510916Y931942D01*
G01X2510934Y932407D02*
X2510921Y932084D01*
G01X2510943Y932611D02*
X2510934Y932407D01*
G01X2512148Y930116D02*
X2512123Y929542D01*
G01X2513337Y930290D02*
X2513358Y930715D01*
G01X2514717Y924105D02*
X2514683Y923506D01*
G01X2510976Y933236D02*
X2510968Y933107D01*
G01X2513412Y931677D02*
X2513430Y931957D01*
G01X2514470Y919941D02*
X2514439Y919486D01*
G01X2512841Y930903D02*
X2512865Y930579D01*
G01D02*
X2512897Y930116D01*
G01X2513506Y919830D02*
X2513529Y919486D01*
G01X2512897Y930116D02*
X2512930Y929633D01*
G01X2517162Y930116D02*
X2517129Y930591D01*
G01X2514064Y930344D02*
X2514110Y929656D01*
G01X2513344Y922474D02*
X2513378Y921894D01*
G01X2513165Y925679D02*
X2513274Y923701D01*
G01X2514457Y923671D02*
X2514324Y926074D01*
G01X2511149Y932084D02*
X2511159Y931785D01*
G01X2511493Y918056D02*
X2511505Y917714D01*
G01X2511485Y918310D02*
X2511493Y918056D01*
G01X2511477Y918580D02*
X2511485Y918310D01*
G01X2512659Y918543D02*
X2512649Y918895D01*
G01D02*
X2512633Y919486D01*
G01X2511200Y930472D02*
X2511209Y930116D01*
G01X2511443Y919811D02*
X2511452Y919486D01*
G01D02*
X2511460Y919164D01*
G01X2511209Y930116D02*
X2511225Y929500D01*
G01X2512633Y919486D02*
X2512616Y920143D01*
G01X2511425Y920520D02*
X2511443Y919811D01*
G01X2511225Y929500D02*
X2511243Y928776D01*
G01X2512616Y920143D02*
X2512597Y920905D01*
G01X2511407Y921292D02*
X2511425Y920520D01*
G01X2511243Y928776D02*
X2511261Y927993D01*
G01X2512597Y920905D02*
X2512578Y921730D01*
G01X2512451Y927609D02*
X2512429Y928581D01*
G01X2511388Y922124D02*
X2511407Y921292D01*
G01X2511261Y927993D02*
X2511280Y927152D01*
G01X2512578Y921730D02*
X2512559Y922615D01*
G01X2511369Y923009D02*
X2511388Y922124D01*
G01X2512473Y926590D02*
X2512451Y927609D01*
G01X2511280Y927152D02*
X2511297Y926378D01*
G01X2512559Y922615D02*
X2512538Y923553D01*
G01X2511297Y926378D02*
X2511369Y923009D01*
G01X2512538Y923553D02*
X2512473Y926590D01*
G01X2504859Y931592D02*
Y931494D01*
G01Y918108D02*
Y918009D01*
G01X2505252Y914761D02*
Y917124D01*
G01Y932478D02*
Y934840D01*
G01X2505646Y918108D02*
Y921257D01*
G01Y928344D02*
Y931494D01*
G01X2506827D02*
Y926966D01*
G01Y922635D02*
Y918108D01*
G01X2507811Y914761D02*
Y917124D01*
G01Y932478D02*
Y934840D01*
G01X2509189Y930116D02*
Y928344D01*
G01Y919486D02*
Y921257D01*
G01X2510370Y932478D02*
Y917124D01*
G01X2510961Y914761D02*
Y917714D01*
G01D02*
Y918698D01*
G01Y930903D02*
Y931887D01*
G01D02*
Y934840D01*
G01X2511158Y926376D02*
Y923226D01*
G01X2511355Y931887D02*
Y931494D01*
G01Y932084D02*
Y931887D01*
G01Y918108D02*
Y917714D01*
G01D02*
Y917517D01*
G01X2513520Y917714D02*
Y931887D01*
G01X2515882Y926966D02*
Y922635D01*
G01X2518835Y926572D02*
Y923029D01*
G01X2510790Y927126D02*
X2510702Y923023D01*
G01X2511883Y923029D02*
X2511970Y927076D01*
G01D02*
X2511988Y927904D01*
G01X2510811Y928050D02*
X2510790Y927126D01*
G01X2511988Y927904D02*
X2512006Y928684D01*
G01X2511800Y919486D02*
X2511816Y920104D01*
G01X2510870Y930446D02*
X2510861Y930116D01*
G01D02*
X2510850Y929716D01*
G01X2512033Y929752D02*
X2512042Y930116D01*
G01X2511781Y918796D02*
X2511800Y919486D01*
G01X2511914Y923319D02*
X2511855Y921249D01*
G01X2513006Y920226D02*
X2513087Y923029D01*
G01X2512042Y930116D02*
X2512059Y930719D01*
G01D02*
X2512066Y930967D01*
G01X2510889Y931101D02*
X2510870Y930446D01*
G01X2511769Y918395D02*
X2511781Y918796D01*
G01X2512985Y919486D02*
X2513006Y920226D01*
G01X2511803Y919486D02*
X2511782Y918797D01*
G01D02*
X2511757Y918011D01*
G01X2513165Y925666D02*
X2513194Y926572D01*
G01D02*
X2513220Y927338D01*
G01X2511748Y917752D02*
X2511757Y918011D01*
G01X2513220Y927338D02*
X2513243Y927973D01*
G01X2511762Y918173D02*
X2511745Y917664D01*
G01X2512928Y917714D02*
X2512941Y918100D01*
G01X2513319Y929876D02*
X2513337Y930290D01*
G01X2515893Y924027D02*
X2516000Y925942D01*
G01X2518916Y922957D02*
X2518953Y923619D01*
G01X2515820Y922733D02*
X2515893Y924027D01*
G01X2517790Y923937D02*
X2517739Y923029D01*
G01X2516000Y925942D02*
X2516035Y926572D01*
G01X2519304Y929652D02*
X2519335Y930116D01*
G01X2492415Y921715D02*
X2492400Y921726D01*
G01X2476097Y915020D02*
X2475426Y916865D01*
G01X2476709Y929722D02*
X2478622Y919880D01*
G01X2478707Y919874D02*
X2476794Y929717D01*
G01X2478787Y919890D02*
X2476874Y929732D01*
G01X2505646Y928344D02*
X2502103Y930470D01*
G01X2491318Y927886D02*
X2491333Y927876D01*
G01X2485764Y924801D02*
X2488914Y921494D01*
G01X2492415Y921519D02*
X2492400Y921539D01*
G01X2491318Y928083D02*
X2491333Y928063D01*
G01X2490987Y921494D02*
X2488914Y924801D01*
G01X2483345Y934581D02*
X2484017Y932737D01*
G01X2496294Y915020D02*
X2495622Y916865D01*
G01X2504290Y934581D02*
X2504961Y932737D01*
G01X2511874Y927170D02*
G03X2511809Y930124I-948192J-19386D01*
G01X2511199Y919480D02*
G03X2511285Y922802I-481490J14127D01*
G01X2513637Y927965D02*
G03X2513520Y929968I-312358J-17241D01*
G01X2511791Y930829D02*
G03X2511761Y931908I-264737J-6821D01*
G01X2512339Y918233D02*
G03X2512361Y918865I-224593J8135D01*
G01X2513510Y930125D02*
G03X2513472Y930730I-206630J-12675D01*
G01X2511158Y918233D02*
G03X2511199Y919481I-153192J5657D01*
G01X2513472Y930730D02*
G03X2513389Y931909I-119582J-7826D01*
G01X2512317Y917676D02*
G03X2512339Y918233I-72717J3151D01*
G01X2476874Y929733D02*
G03X2476709Y929722I3814J-58460D01*
G01X2478787Y919890D02*
G03X2478622Y919880I3462J-58481D01*
G01X2478679Y919876D02*
G03X2478622Y919879I-1207J-22396D01*
G01X2494982Y920624D02*
G03X2494725Y920623I-52J-19629D01*
G01X2476794Y929717D02*
G03X2476709Y929722I-968J-15727D01*
G01X2478707Y919874D02*
G03X2478679Y919876I-715J-9810D01*
G01X2476097Y915020D02*
G03X2476467Y914761I370J135D01*
G01X2482975D02*
G03X2483345Y915020I0J394D01*
G01X2465685Y917124D02*
G03X2468048Y914761I2362J-1D01*
G01X2482426Y919781D02*
G03I-1279J0D01*
G01X2476315Y919880D02*
G03X2475528Y919092I1J-788D01*
G01X2470410Y918108D02*
G03X2469622Y918895I-787J0D01*
G01X2468835Y922439D02*
G03X2468048Y921651I0J-787D01*
G01X2481827Y917419D02*
G03X2482418Y918009I0J591D01*
G01X2479268D02*
G03X2479859Y917419I591J1D01*
G01X2481639Y919781D02*
G03I-492J0D01*
G01X2475426Y916865D02*
G03X2475056Y917124I-370J-135D01*
G01X2484386D02*
G03X2484017Y916865I1J-394D01*
G01X2494875Y928885D02*
G03X2494691Y928884I16J-19811D01*
G01X2494948Y928885D02*
G03X2494875I-36J-18949D01*
G01X2503920Y914761D02*
G03X2504290Y915020I0J394D01*
G01X2496294D02*
G03X2496663Y914761I370J135D01*
G01X2505056Y919781D02*
G03I-1280J0D01*
G01X2504268Y917419D02*
G03X2504859Y918009I0J591D01*
G01X2501709D02*
G03X2502300Y917419I591J1D01*
G01X2504268Y919781D02*
G03I-492J0D01*
G01X2501512Y920864D02*
G03X2501860Y921442I0J394D01*
G01X2505331Y917124D02*
G03X2504961Y916865I0J-394D01*
G01X2495622D02*
G03X2495252Y917124I-370J-135D01*
G01X2473697Y924801D02*
G03I-2893J0D01*
G01X2471985Y922439D02*
G03Y927163I0J2362D01*
G01X2472474Y924801D02*
G03I-1670J0D01*
G01X2468048Y927950D02*
G03X2468835Y927163I787J0D01*
G01X2484691Y923422D02*
G03X2484780Y923417I92J835D01*
G01X2484623Y924063D02*
G03X2484592Y924057I137J-790D01*
G01X2484780Y924309D02*
G03X2484288Y923817I0J-492D01*
G01X2484780Y924112D02*
G03X2484485Y923817I0J-295D01*
G01X2484288Y923324D02*
G03X2484485Y923521I0J197D01*
G01X2484592Y925544D02*
G03X2484623Y925538I168J784D01*
G01X2484288Y925785D02*
G03X2484780Y925293I492J0D01*
G01X2484485Y925785D02*
G03X2484780Y925490I295J0D01*
G01X2484485Y926080D02*
G03X2484288Y926277I-197J0D01*
G01X2468048Y934840D02*
G03X2465685Y932478I-1J-2362D01*
G01X2482426Y929624D02*
G03I-1279J0D01*
G01X2469622Y930706D02*
G03X2470410Y931494I0J788D01*
G01X2475528Y930509D02*
G03X2476315Y929722I787J0D01*
G01X2479859Y932183D02*
G03X2479268Y931592I0J-591D01*
G01X2482418D02*
G03X2481827Y932183I-591J0D01*
G01X2481639Y929624D02*
G03I-492J0D01*
G01X2475056Y932478D02*
G03X2475426Y932737I0J394D01*
G01X2476467Y934840D02*
G03X2476097Y934581I0J-394D01*
G01X2483345D02*
G03X2482975Y934840I-370J-135D01*
G01X2484017Y932737D02*
G03X2484386Y932478I370J134D01*
G01X2490587Y923817D02*
G03X2490546Y924013I-492J-1D01*
G01X2490390Y923817D02*
G03X2490315Y924013I-295J-1D01*
G01X2490390Y923521D02*
G03X2490587Y923324I197J0D01*
G01X2490183Y926179D02*
G03X2490095Y926185I-101J-834D01*
G01X2490546Y925588D02*
G03X2490587Y925785I-451J197D01*
G01X2490315Y925588D02*
G03X2490390Y925785I-220J197D01*
G01X2493550Y923422D02*
G03X2493638Y923417I92J835D01*
G01Y924309D02*
G03X2493441Y924267I2J-492D01*
G01X2493187Y924013D02*
G03X2493146Y923817I451J-197D01*
G01X2493638Y924112D02*
G03X2493441Y924037I0J-296D01*
G01X2493418Y924013D02*
G03X2493343Y923817I220J-197D01*
G01X2493146Y923324D02*
G03X2493343Y923521I0J197D01*
G01X2493146Y925785D02*
G03X2493187Y925588I492J0D01*
G01X2493441Y925334D02*
G03X2493638Y925293I197J451D01*
G01X2493343Y925785D02*
G03X2493418Y925588I295J0D01*
G01X2493441Y925565D02*
G03X2493638Y925490I197J220D01*
G01X2493538Y925530D02*
G03X2493638Y925524I105J909D01*
G01X2493441Y925546D02*
G03X2493538Y925530I184J814D01*
G01X2490587Y926277D02*
G03X2490390Y926080I0J-197D01*
G01X2493343D02*
G03X2493146Y926277I-197J0D01*
G01X2505828Y922869D02*
G03Y926732I-379J1931D01*
G01X2499042Y926179D02*
G03X2498953Y926185I-101J-834D01*
G01X2499445Y923817D02*
G03X2499404Y924013I-492J-1D01*
G01Y925588D02*
G03X2499445Y925785I-451J197D01*
G01X2499368Y923957D02*
G03X2499347Y923973I-218J-265D01*
G01X2499248Y923817D02*
G03X2499173Y924013I-295J-1D01*
G01Y925588D02*
G03X2499248Y925785I-220J197D01*
G01Y923521D02*
G03X2499445Y923324I197J0D01*
G01X2501860Y928159D02*
G03X2501512Y928738I-348J185D01*
G01X2499445Y926277D02*
G03X2499248Y926080I0J-197D01*
G01X2519418Y933324D02*
G03X2519405Y933434I-14998J-1717D01*
G01X2505056Y929624D02*
G03I-1280J0D01*
G01X2494876Y928870D02*
G03Y928884I-791J7D01*
G01X2502300Y932183D02*
G03X2501709Y931592I0J-591D01*
G01X2504859D02*
G03X2504268Y932183I-591J0D01*
G01Y929624D02*
G03I-492J0D01*
G01X2495252Y932478D02*
G03X2495622Y932737I0J394D01*
G01X2496663Y934840D02*
G03X2496294Y934581I1J-394D01*
G01X2504290D02*
G03X2503920Y934840I-370J-135D01*
G01X2504961Y932737D02*
G03X2505331Y932478I370J135D01*
G01X2517412Y916511D02*
G03X2517441Y916263I18660J2056D01*
G01X2510961Y918698D02*
G03X2506794Y917124I-1J-6299D01*
G01X2510961Y916336D02*
G03X2507811Y914761I0J-3937D01*
G01X2513520Y921651D02*
G03X2512733Y922439I-788J0D01*
G01X2512142Y918895D02*
G03X2511355Y918108I0J-787D01*
G01X2511158Y918233D02*
G03X2510960Y918205I2J-727D01*
G01Y917322D02*
G03X2511158Y917295I196J700D01*
G01X2511370Y918201D02*
G03X2511158Y918233I-213J-695D01*
G01X2511745Y917713D02*
G03X2511748Y917752I-360J47D01*
G01D02*
G03Y917775I-354J11D01*
G01X2501612Y922039D02*
G03X2501860Y921442I7490J2762D01*
G01Y928159D02*
G03X2501612Y927563I7241J-3362D01*
G01D02*
G03Y922039I7490J-2762D01*
G01X2513520Y928762D02*
G03Y920839I0J-3962D01*
G01Y927507D02*
G03Y922094I0J-2707D01*
G01X2507144Y923809D02*
G03Y925793I-711J992D01*
G01D02*
G03Y923809I-711J-992D01*
G01X2511355Y931494D02*
G03X2512142Y930706I787J-1D01*
G01X2512733Y927163D02*
G03X2513520Y927950I0J787D01*
G01X2511945Y927163D02*
G03X2511158Y926376I0J-787D01*
G01Y923226D02*
G03X2511945Y922439I787J0D01*
G01X2506794Y932478D02*
G03X2510961Y930903I4167J4724D01*
G01X2507811Y934840D02*
G03X2510961Y933265I3150J2362D01*
G01X2512757Y930126D02*
G03X2512734Y929669I122177J-6378D01*
G01X2511508Y931502D02*
G03X2511493Y931089I112829J-4305D01*
G01X2512791Y930736D02*
G03X2512757Y930126I89014J-5267D01*
G01X2511526Y931923D02*
G03X2511512Y931602I68796J-3161D01*
G01X2512820Y931206D02*
G03X2512791Y930736I61912J-4056D01*
G01X2512049Y918852D02*
G03X2512081Y917689I239853J6018D01*
G01X2512734Y929669D02*
G03X2512635Y927325I205057J-9835D01*
G01X2511493Y931089D02*
G03X2511463Y930138I194142J-6600D01*
G01X2511969Y922430D02*
G03X2512033Y919483I776769J15395D01*
G01X2511463Y930138D02*
G03X2511380Y926920I609652J-17334D01*
G01X2512609Y926582D02*
G03X2512526Y924109I600834J-21403D01*
G01X2511285Y922802D02*
X2511290Y923020D01*
G01D02*
X2511294Y923214D01*
G01D02*
X2511331Y924800D01*
G01D02*
X2511367Y926378D01*
G01D02*
X2511371Y926582D01*
G01D02*
X2511379Y926920D01*
G01X2511508Y931502D02*
X2511512Y931602D01*
G01X2512635Y927325D02*
X2512630Y927171D01*
G01D02*
X2512608Y926581D01*
G01X2512526Y924109D02*
X2512492Y923020D01*
G01D02*
X2512474Y922443D01*
G01X2512382Y919478D02*
X2512362Y918865D01*
G01X2515239Y923022D02*
X2515452Y926577D01*
G01X2518322Y923025D02*
X2518535Y926574D01*
G01X2499124Y926165D02*
X2499153Y926157D01*
G01X2512049Y918852D02*
Y918864D01*
G01D02*
X2512033Y919483D01*
G01X2511969Y922429D02*
X2511874Y927170D01*
G01X2511809Y930123D02*
X2511791Y930829D01*
G01X2513510Y930125D02*
X2513520Y929968D01*
G01X2513660Y927528D02*
X2513637Y927965D01*
G01X2513389Y931920D02*
Y931909D01*
G01X2518720Y933353D02*
X2518729Y933326D01*
G01D02*
X2518745Y933263D01*
G01D02*
X2518764Y933170D01*
G01D02*
X2518786Y933049D01*
G01D02*
X2518809Y932900D01*
G01D02*
X2518832Y932725D01*
G01D02*
X2518857Y932524D01*
G01D02*
X2518882Y932296D01*
G01D02*
X2518908Y932043D01*
G01D02*
X2518934Y931764D01*
G01D02*
X2518961Y931459D01*
G01D02*
X2518988Y931130D01*
G01D02*
X2519015Y930776D01*
G01D02*
X2519043Y930396D01*
G01X2512575Y933384D02*
X2512576Y933382D01*
G01D02*
X2512583Y933356D01*
G01D02*
X2512594Y933305D01*
G01D02*
X2512608Y933232D01*
G01D02*
X2512624Y933141D01*
G01D02*
X2512640Y933032D01*
G01D02*
X2512657Y932905D01*
G01D02*
X2512675Y932759D01*
G01D02*
X2512694Y932596D01*
G01D02*
X2512713Y932413D01*
G01D02*
X2512733Y932212D01*
G01D02*
X2512753Y931991D01*
G01D02*
X2512762Y931887D01*
G01X2515638Y933353D02*
X2515645Y933330D01*
G01D02*
X2515659Y933274D01*
G01D02*
X2515678Y933189D01*
G01D02*
X2515698Y933077D01*
G01D02*
X2515720Y932940D01*
G01D02*
X2515742Y932780D01*
G01D02*
X2515765Y932596D01*
G01D02*
X2515789Y932389D01*
G01D02*
X2515813Y932159D01*
G01D02*
X2515838Y931904D01*
G01D02*
X2515863Y931626D01*
G01D02*
X2515889Y931323D01*
G01D02*
X2515915Y930995D01*
G01D02*
X2515942Y930644D01*
G01D02*
X2515969Y930267D01*
G01X2515054Y916246D02*
X2515046Y916270D01*
G01D02*
X2515032Y916327D01*
G01D02*
X2515014Y916412D01*
G01D02*
X2514994Y916522D01*
G01D02*
X2514972Y916656D01*
G01D02*
X2514950Y916815D01*
G01D02*
X2514927Y916997D01*
G01D02*
X2514903Y917203D01*
G01D02*
X2514878Y917433D01*
G01D02*
X2514854Y917687D01*
G01D02*
X2514828Y917966D01*
G01D02*
X2514803Y918268D01*
G01D02*
X2514776Y918593D01*
G01D02*
X2514750Y918942D01*
G01D02*
X2514723Y919314D01*
G01X2512775Y916109D02*
Y916108D01*
G01D02*
X2512772Y916127D01*
G01D02*
X2512768Y916161D01*
G01D02*
X2512763Y916209D01*
G01D02*
X2512757Y916269D01*
G01D02*
X2512752Y916341D01*
G01D02*
X2512746Y916425D01*
G01D02*
X2512739Y916522D01*
G01D02*
X2512733Y916631D01*
G01D02*
X2512726Y916754D01*
G01D02*
X2512720Y916890D01*
G01D02*
X2512713Y917041D01*
G01D02*
X2512706Y917207D01*
G01D02*
X2512698Y917388D01*
G01D02*
X2512691Y917585D01*
G01D02*
X2512686Y917714D01*
G01X2511067Y933494D02*
X2511070Y933477D01*
G01D02*
X2511074Y933445D01*
G01D02*
X2511079Y933399D01*
G01X2518137Y916248D02*
X2518127Y916278D01*
G01D02*
X2518111Y916343D01*
G01D02*
X2518091Y916439D01*
G01D02*
X2518069Y916564D01*
G01D02*
X2518046Y916718D01*
G01D02*
X2518022Y916900D01*
G01D02*
X2517996Y917111D01*
G01D02*
X2517970Y917350D01*
G01D02*
X2517943Y917618D01*
G01D02*
X2517916Y917914D01*
G01D02*
X2517888Y918239D01*
G01D02*
X2517859Y918593D01*
G01D02*
X2517830Y918975D01*
G01D02*
X2517800Y919387D01*
G01X2519676Y919754D02*
X2519710Y919270D01*
G01D02*
X2519742Y918823D01*
G01D02*
X2519774Y918413D01*
G01D02*
X2519805Y918037D01*
G01D02*
X2519835Y917695D01*
G01D02*
X2519865Y917385D01*
G01D02*
X2519894Y917104D01*
G01X2519043Y930396D02*
X2519072Y929991D01*
G01D02*
X2519101Y929562D01*
G01D02*
X2519130Y929109D01*
G01D02*
X2519160Y928632D01*
G01D02*
X2519190Y928133D01*
G01D02*
X2519221Y927612D01*
G01D02*
X2519252Y927069D01*
G01D02*
X2519285Y926502D01*
G01D02*
X2519318Y925914D01*
G01X2519899Y933503D02*
X2519868Y933628D01*
G01D02*
X2519832Y933743D01*
G01D02*
X2519784Y933860D01*
G01D02*
X2519703Y933993D01*
G01D02*
X2519548Y934141D01*
G01D02*
X2519289Y934242D01*
G01D02*
X2519198Y934248D01*
G01X2519335Y930116D02*
X2519360Y930469D01*
G01D02*
X2519388Y930841D01*
G01D02*
X2519415Y931188D01*
G01D02*
X2519442Y931510D01*
G01D02*
X2519468Y931806D01*
G01D02*
X2519494Y932076D01*
G01D02*
X2519519Y932321D01*
G01D02*
X2519543Y932540D01*
G01D02*
X2519567Y932734D01*
G01D02*
X2519591Y932904D01*
G01D02*
X2519613Y933048D01*
G01D02*
X2519634Y933168D01*
G01D02*
X2519653Y933261D01*
G01D02*
X2519669Y933325D01*
G01D02*
X2519670Y933330D01*
G01X2518704Y919486D02*
X2518728Y919841D01*
G01D02*
X2518764Y920401D01*
G01D02*
X2518802Y921002D01*
G01D02*
X2518840Y921637D01*
G01D02*
X2518878Y922292D01*
G01D02*
X2518916Y922957D01*
G01X2519185Y927743D02*
X2519216Y928253D01*
G01D02*
X2519245Y928742D01*
G01D02*
X2519275Y929208D01*
G01D02*
X2519304Y929652D01*
G01X2516100Y927700D02*
X2516132Y928240D01*
G01D02*
X2516163Y928755D01*
G01D02*
X2516194Y929244D01*
G01D02*
X2516224Y929706D01*
G01X2517687Y922126D02*
X2517655Y921576D01*
G01D02*
X2517623Y921054D01*
G01D02*
X2517593Y920557D01*
G01D02*
X2517562Y920087D01*
G01D02*
X2517532Y919641D01*
G01X2516035Y926572D02*
X2516067Y927136D01*
G01D02*
X2516100Y927700D01*
G01X2517739Y923029D02*
X2517720Y922702D01*
G01D02*
X2517687Y922126D01*
G01X2517938Y926591D02*
X2517900Y925929D01*
G01D02*
X2517790Y923937D01*
G01X2518953Y923619D02*
X2519091Y926096D01*
G01D02*
X2519123Y926665D01*
G01D02*
X2519154Y927214D01*
G01D02*
X2519185Y927743D01*
G01X2513243Y927973D02*
X2513262Y928484D01*
G01D02*
X2513281Y928972D01*
G01D02*
X2513300Y929437D01*
G01D02*
X2513319Y929876D01*
G01X2511745Y917664D02*
X2511737Y917454D01*
G01D02*
X2511729Y917258D01*
G01D02*
X2511722Y917078D01*
G01D02*
X2511714Y916913D01*
G01D02*
X2511707Y916763D01*
G01D02*
X2511700Y916630D01*
G01D02*
X2511693Y916512D01*
G01D02*
X2511686Y916409D01*
G01D02*
X2511680Y916322D01*
G01D02*
X2511674Y916250D01*
G01D02*
X2511668Y916192D01*
G01D02*
X2511663Y916148D01*
G01D02*
X2511659Y916119D01*
G01D02*
X2511658Y916113D01*
G01X2512090Y931717D02*
X2512097Y931936D01*
G01D02*
X2512105Y932139D01*
G01D02*
X2512112Y932327D01*
G01D02*
X2512119Y932499D01*
G01D02*
X2512126Y932657D01*
G01D02*
X2512133Y932800D01*
G01D02*
X2512140Y932929D01*
G01D02*
X2512147Y933045D01*
G01D02*
X2512153Y933148D01*
G01D02*
X2512159Y933238D01*
G01D02*
X2512165Y933315D01*
G01D02*
X2512171Y933380D01*
G01D02*
X2512176Y933432D01*
G01D02*
X2512181Y933470D01*
G01D02*
X2512184Y933492D01*
G01D02*
Y933493D01*
G01X2510916Y931942D02*
X2510907Y931681D01*
G01D02*
X2510898Y931400D01*
G01D02*
X2510889Y931101D01*
G01X2512941Y918100D02*
X2512957Y918588D01*
G01D02*
X2512985Y919486D01*
G01X2512013Y926572D02*
X2511996Y926039D01*
G01D02*
X2511975Y925377D01*
G01D02*
X2511955Y924700D01*
G01D02*
X2511934Y924013D01*
G01D02*
X2511914Y923319D01*
G01X2512066Y930967D02*
X2512074Y931233D01*
G01D02*
X2512082Y931483D01*
G01D02*
X2512090Y931717D01*
G01X2510604Y918937D02*
X2510591Y918491D01*
G01D02*
X2510578Y918070D01*
G01D02*
X2510568Y917776D01*
G01X2513087Y923029D02*
X2513112Y923904D01*
G01D02*
X2513130Y924522D01*
G01D02*
X2513149Y925132D01*
G01D02*
X2513165Y925666D01*
G01X2511855Y921249D02*
X2511835Y920581D01*
G01D02*
X2511817Y919933D01*
G01D02*
X2511803Y919486D01*
G01X2510630Y919891D02*
X2510617Y919405D01*
G01D02*
X2510604Y918937D01*
G01X2510850Y929716D02*
X2510841Y929325D01*
G01D02*
X2510831Y928916D01*
G01D02*
X2510811Y928050D01*
G01X2511816Y920104D02*
X2511827Y920563D01*
G01D02*
X2511839Y921030D01*
G01D02*
X2511849Y921503D01*
G01D02*
X2511883Y923029D01*
G01X2512006Y928684D02*
X2512024Y929410D01*
G01D02*
X2512033Y929752D01*
G01X2510702Y923023D02*
X2510678Y921956D01*
G01D02*
X2510667Y921428D01*
G01D02*
X2510654Y920906D01*
G01D02*
X2510642Y920392D01*
G01D02*
X2510630Y919891D01*
G01X2512429Y928581D02*
X2512418Y929041D01*
G01D02*
X2512407Y929479D01*
G01D02*
X2512396Y929892D01*
G01D02*
X2512376Y930641D01*
G01X2511460Y919164D02*
X2511469Y918864D01*
G01D02*
X2511477Y918580D01*
G01X2512376Y930641D02*
X2512367Y930977D01*
G01D02*
X2512357Y931289D01*
G01D02*
X2512348Y931579D01*
G01D02*
X2512337Y931887D01*
G01X2511159Y931785D02*
X2511167Y931553D01*
G01D02*
X2511175Y931305D01*
G01D02*
X2511183Y931043D01*
G01D02*
X2511192Y930765D01*
G01D02*
X2511200Y930472D01*
G01X2512686Y917714D02*
X2512676Y918029D01*
G01D02*
X2512667Y918277D01*
G01D02*
X2512659Y918543D01*
G01X2511505Y917714D02*
X2511509Y917591D01*
G01D02*
X2511517Y917380D01*
G01D02*
X2511525Y917184D01*
G01D02*
X2511533Y917002D01*
G01D02*
X2511540Y916835D01*
G01D02*
X2511548Y916683D01*
G01D02*
X2511555Y916546D01*
G01D02*
X2511563Y916422D01*
G01D02*
X2511570Y916313D01*
G01D02*
X2511577Y916216D01*
G01D02*
X2511585Y916131D01*
G01D02*
X2511592Y916056D01*
G01D02*
X2511600Y915990D01*
G01D02*
X2511608Y915929D01*
G01D02*
X2511620Y915868D01*
G01D02*
X2511638Y915796D01*
G01D02*
X2511676Y915696D01*
G01D02*
X2511765Y915559D01*
G01D02*
X2511918Y915433D01*
G01D02*
X2512129Y915359D01*
G01D02*
X2512216Y915352D01*
G01X2512337Y931887D02*
X2512330Y932093D01*
G01D02*
X2512321Y932319D01*
G01D02*
X2512313Y932524D01*
G01D02*
X2512305Y932711D01*
G01D02*
X2512296Y932879D01*
G01D02*
X2512289Y933028D01*
G01D02*
X2512281Y933161D01*
G01D02*
X2512273Y933278D01*
G01D02*
X2512265Y933380D01*
G01D02*
X2512258Y933469D01*
G01D02*
X2512250Y933546D01*
G01D02*
X2512242Y933614D01*
G01D02*
X2512233Y933675D01*
G01D02*
X2512222Y933736D01*
G01D02*
X2512204Y933807D01*
G01D02*
X2512163Y933911D01*
G01D02*
X2512069Y934051D01*
G01D02*
X2511907Y934177D01*
G01D02*
X2511692Y934245D01*
G01D02*
X2511626Y934249D01*
G01X2519318Y925914D02*
X2519386Y924675D01*
G01D02*
X2519459Y923371D01*
G01X2517537Y923731D02*
X2517463Y925057D01*
G01D02*
X2517426Y925723D01*
G01D02*
X2517390Y926378D01*
G01D02*
X2517354Y927012D01*
G01D02*
X2517319Y927617D01*
G01D02*
X2517285Y928190D01*
G01D02*
X2517252Y928730D01*
G01D02*
X2517220Y929239D01*
G01D02*
X2517189Y929719D01*
G01D02*
X2517162Y930116D01*
G01X2516235Y925896D02*
X2516301Y924719D01*
G01D02*
X2516370Y923480D01*
G01X2513274Y923701D02*
X2513309Y923077D01*
G01D02*
X2513344Y922474D01*
G01X2516370Y923480D02*
X2516406Y922843D01*
G01D02*
X2516443Y922201D01*
G01D02*
X2516480Y921566D01*
G01D02*
X2516517Y920947D01*
G01D02*
X2516554Y920356D01*
G01D02*
X2516590Y919800D01*
G01X2514324Y926074D02*
X2514289Y926698D01*
G01D02*
X2514253Y927327D01*
G01D02*
X2514216Y927955D01*
G01D02*
X2514179Y928579D01*
G01D02*
X2514140Y929194D01*
G01D02*
X2514110Y929656D01*
G01X2519459Y923371D02*
X2519496Y922714D01*
G01D02*
X2519533Y922067D01*
G01D02*
X2519570Y921440D01*
G01D02*
X2519607Y920841D01*
G01D02*
X2519642Y920278D01*
G01D02*
X2519676Y919754D01*
G01X2513047Y927746D02*
X2513087Y927054D01*
G01D02*
X2513126Y926363D01*
G01D02*
X2513165Y925679D01*
G01X2513378Y921894D02*
X2513410Y921339D01*
G01D02*
X2513443Y920809D01*
G01D02*
X2513474Y920306D01*
G01D02*
X2513506Y919830D01*
G01X2512930Y929633D02*
X2512964Y929111D01*
G01D02*
X2513006Y928434D01*
G01D02*
X2513047Y927746D01*
G01X2513529Y919486D02*
X2513536Y919382D01*
G01D02*
X2513566Y918962D01*
G01X2516590Y919800D02*
X2516626Y919287D01*
G01D02*
X2516659Y918821D01*
G01D02*
X2516692Y918399D01*
G01D02*
X2516723Y918018D01*
G01D02*
X2516754Y917674D01*
G01D02*
X2516783Y917364D01*
G01D02*
X2516812Y917086D01*
G01D02*
X2516841Y916840D01*
G01D02*
X2516869Y916622D01*
G01D02*
X2516897Y916431D01*
G01D02*
X2516925Y916264D01*
G01D02*
X2516954Y916118D01*
G01D02*
X2516985Y915989D01*
G01D02*
X2517020Y915871D01*
G01D02*
X2517067Y915754D01*
G01D02*
X2517144Y915620D01*
G01D02*
X2517293Y915471D01*
G01D02*
X2517550Y915362D01*
G01D02*
X2517658Y915352D01*
G01X2517800Y919387D02*
X2517770Y919829D01*
G01D02*
X2517739Y920300D01*
G01D02*
X2517707Y920800D01*
G01D02*
X2517675Y921330D01*
G01D02*
X2517642Y921889D01*
G01D02*
X2517608Y922476D01*
G01D02*
X2517573Y923091D01*
G01D02*
X2517537Y923731D01*
G01X2515969Y930267D02*
X2515997Y929868D01*
G01D02*
X2516025Y929445D01*
G01D02*
X2516054Y929000D01*
G01D02*
X2516083Y928532D01*
G01D02*
X2516112Y928043D01*
G01D02*
X2516142Y927535D01*
G01D02*
X2516173Y927007D01*
G01D02*
X2516204Y926461D01*
G01D02*
X2516235Y925896D01*
G01X2514723Y919314D02*
X2514695Y919710D01*
G01D02*
X2514667Y920129D01*
G01D02*
X2514639Y920572D01*
G01D02*
X2514610Y921036D01*
G01D02*
X2514581Y921523D01*
G01D02*
X2514551Y922031D01*
G01D02*
X2514520Y922559D01*
G01D02*
X2514489Y923106D01*
G01D02*
X2514457Y923671D01*
G01X2514064Y930344D02*
X2514037Y930727D01*
G01D02*
X2514011Y931083D01*
G01D02*
X2513985Y931415D01*
G01D02*
X2513960Y931722D01*
G01D02*
X2513936Y932004D01*
G01D02*
X2513913Y932262D01*
G01D02*
X2513890Y932496D01*
G01D02*
X2513868Y932709D01*
G01D02*
X2513846Y932901D01*
G01D02*
X2513825Y933073D01*
G01D02*
X2513804Y933226D01*
G01D02*
X2513783Y933362D01*
G01D02*
X2513761Y933483D01*
G01D02*
X2513739Y933593D01*
G01D02*
X2513713Y933691D01*
G01D02*
X2513683Y933787D01*
G01D02*
X2513637Y933892D01*
G01D02*
X2513554Y934021D01*
G01D02*
X2513393Y934160D01*
G01D02*
X2513146Y934244D01*
G01D02*
X2513076Y934249D01*
G01X2517129Y930591D02*
X2517099Y930986D01*
G01D02*
X2517070Y931354D01*
G01D02*
X2517041Y931695D01*
G01D02*
X2517013Y932009D01*
G01D02*
X2516985Y932296D01*
G01D02*
X2516957Y932557D01*
G01D02*
X2516929Y932791D01*
G01D02*
X2516902Y933000D01*
G01D02*
X2516874Y933186D01*
G01D02*
X2516847Y933350D01*
G01D02*
X2516818Y933494D01*
G01D02*
X2516787Y933622D01*
G01D02*
X2516751Y933739D01*
G01D02*
X2516702Y933857D01*
G01D02*
X2516621Y933992D01*
G01D02*
X2516465Y934140D01*
G01D02*
X2516205Y934241D01*
G01D02*
X2516116Y934248D01*
G01X2513566Y918962D02*
X2513596Y918570D01*
G01D02*
X2513625Y918205D01*
G01D02*
X2513654Y917867D01*
G01X2512762Y931887D02*
X2512774Y931750D01*
G01D02*
X2512796Y931488D01*
G01D02*
X2512819Y931206D01*
G01D02*
X2512841Y930903D01*
G01X2513654Y917867D02*
X2513681Y917556D01*
G01D02*
X2513709Y917273D01*
G01D02*
X2513737Y917017D01*
G01D02*
X2513765Y916787D01*
G01D02*
X2513792Y916583D01*
G01D02*
X2513819Y916402D01*
G01D02*
X2513846Y916243D01*
G01D02*
X2513874Y916102D01*
G01D02*
X2513905Y915976D01*
G01D02*
X2513941Y915860D01*
G01D02*
X2513989Y915743D01*
G01D02*
X2514069Y915609D01*
G01D02*
X2514222Y915462D01*
G01D02*
X2514477Y915360D01*
G01D02*
X2514575Y915352D01*
G01X2511079Y933399D02*
X2511084Y933341D01*
G01D02*
X2511090Y933269D01*
G01D02*
X2511096Y933186D01*
G01D02*
X2511102Y933089D01*
G01D02*
X2511109Y932980D01*
G01D02*
X2511115Y932856D01*
G01D02*
X2511122Y932716D01*
G01D02*
X2511130Y932561D01*
G01D02*
X2511137Y932391D01*
G01D02*
X2511144Y932204D01*
G01D02*
X2511149Y932084D01*
G01X2511658Y916113D02*
X2511657Y916106D01*
G01D02*
X2511659Y916114D01*
G01D02*
X2511670Y916151D01*
G01D02*
X2511706Y916231D01*
G01D02*
X2511789Y916348D01*
G01D02*
X2511944Y916465D01*
G01D02*
X2512157Y916530D01*
G01D02*
X2512216Y916533D01*
G01X2511000Y933530D02*
X2510992Y933446D01*
G01D02*
X2510984Y933349D01*
G01D02*
X2510976Y933236D01*
G01X2512305Y932709D02*
X2512289Y932524D01*
G01D02*
X2512269Y932262D01*
G01D02*
X2512248Y931970D01*
G01X2514439Y919486D02*
X2514413Y919125D01*
G01D02*
X2514385Y918754D01*
G01D02*
X2514358Y918407D01*
G01D02*
X2514331Y918084D01*
G01D02*
X2514305Y917787D01*
G01D02*
X2514279Y917515D01*
G01D02*
X2514254Y917268D01*
G01D02*
X2514229Y917047D01*
G01D02*
X2514205Y916852D01*
G01D02*
X2514181Y916683D01*
G01D02*
X2514159Y916540D01*
G01D02*
X2514138Y916423D01*
G01D02*
X2514119Y916333D01*
G01D02*
X2514104Y916273D01*
G01D02*
X2514102Y916269D01*
G01X2513430Y931957D02*
X2513448Y932210D01*
G01D02*
X2513466Y932437D01*
G01D02*
X2513483Y932641D01*
G01D02*
X2513500Y932819D01*
G01D02*
X2513517Y932974D01*
G01D02*
X2513532Y933105D01*
G01D02*
X2513548Y933213D01*
G01D02*
X2513561Y933296D01*
G01D02*
X2513573Y933356D01*
G01D02*
X2513581Y933389D01*
G01D02*
Y933391D01*
G01X2517532Y919641D02*
X2517503Y919220D01*
G01D02*
X2517474Y918826D01*
G01D02*
X2517445Y918458D01*
G01D02*
X2517417Y918119D01*
G01D02*
X2517390Y917807D01*
G01D02*
X2517363Y917524D01*
G01D02*
X2517337Y917269D01*
G01D02*
X2517311Y917044D01*
G01D02*
X2517287Y916846D01*
G01D02*
X2517263Y916676D01*
G01D02*
X2517241Y916533D01*
G01D02*
X2517220Y916417D01*
G01D02*
X2517201Y916328D01*
G01D02*
X2517186Y916270D01*
G01D02*
X2517185Y916265D01*
G01X2518154Y930116D02*
X2518143Y929960D01*
G01D02*
X2518111Y929483D01*
G01D02*
X2518078Y928973D01*
G01D02*
X2518045Y928429D01*
G01D02*
X2518010Y927849D01*
G01D02*
X2517974Y927234D01*
G01D02*
X2517938Y926591D01*
G01X2516224Y929706D02*
X2516254Y930141D01*
G01D02*
X2516283Y930548D01*
G01D02*
X2516312Y930930D01*
G01D02*
X2516340Y931284D01*
G01D02*
X2516368Y931611D01*
G01D02*
X2516395Y931911D01*
G01D02*
X2516422Y932185D01*
G01D02*
X2516448Y932431D01*
G01D02*
X2516474Y932651D01*
G01D02*
X2516499Y932843D01*
G01D02*
X2516523Y933006D01*
G01D02*
X2516546Y933140D01*
G01D02*
X2516566Y933245D01*
G01D02*
X2516583Y933317D01*
G01D02*
X2516585Y933322D01*
G01X2515070Y930116D02*
X2515044Y929731D01*
G01D02*
X2515009Y929193D01*
G01D02*
X2514973Y928613D01*
G01D02*
X2514936Y927998D01*
G01D02*
X2514898Y927356D01*
G01D02*
X2514861Y926696D01*
G01X2515620Y919486D02*
X2515648Y919885D01*
G01D02*
X2515680Y920389D01*
G01D02*
X2515714Y920928D01*
G01D02*
X2515749Y921502D01*
G01D02*
X2515784Y922106D01*
G01D02*
X2515820Y922733D01*
G01X2512862Y916298D02*
X2512869Y916404D01*
G01D02*
X2512876Y916525D01*
G01D02*
X2512884Y916660D01*
G01D02*
X2512891Y916813D01*
G01D02*
X2512899Y916982D01*
G01D02*
X2512907Y917171D01*
G01D02*
X2512916Y917380D01*
G01D02*
X2512928Y917714D01*
G01X2512248Y931970D02*
X2512228Y931646D01*
G01D02*
X2512207Y931291D01*
G01D02*
X2512186Y930902D01*
G01X2514588Y921846D02*
X2514557Y921337D01*
G01D02*
X2514528Y920850D01*
G01D02*
X2514498Y920384D01*
G01D02*
X2514470Y919941D01*
G01X2512184Y933493D02*
X2512185D01*
G01D02*
X2512178Y933467D01*
G01D02*
X2512148Y933393D01*
G01D02*
X2512068Y933270D01*
G01D02*
X2511919Y933147D01*
G01D02*
X2511709Y933074D01*
G01D02*
X2511626Y933068D01*
G01X2514683Y923506D02*
X2514650Y922930D01*
G01D02*
X2514619Y922377D01*
G01D02*
X2514588Y921846D01*
G01X2514861Y926696D02*
X2514823Y926031D01*
G01D02*
X2514717Y924105D01*
G01X2510968Y933107D02*
X2510959Y932960D01*
G01D02*
X2510951Y932795D01*
G01D02*
X2510943Y932611D01*
G01X2513358Y930715D02*
X2513375Y931038D01*
G01D02*
X2513393Y931371D01*
G01D02*
X2513412Y931677D01*
G01X2512186Y930902D02*
X2512165Y930481D01*
G01D02*
X2512148Y930116D01*
G01X2512123Y929542D02*
X2512102Y929026D01*
G01D02*
X2512080Y928480D01*
G01D02*
X2512059Y927907D01*
G01D02*
X2512038Y927307D01*
G01D02*
X2512013Y926572D01*
G01X2514575Y916533D02*
X2514653Y916527D01*
G01D02*
X2514876Y916444D01*
G01D02*
X2515000Y916333D01*
G01D02*
X2515046Y916264D01*
G01D02*
X2515054Y916246D01*
G01X2512216Y916533D02*
X2512298Y916527D01*
G01D02*
X2512506Y916456D01*
G01D02*
X2512656Y916334D01*
G01D02*
X2512738Y916210D01*
G01D02*
X2512768Y916135D01*
G01D02*
X2512775Y916109D01*
G01X2517658Y916533D02*
X2517733Y916528D01*
G01D02*
X2517957Y916446D01*
G01D02*
X2518084Y916333D01*
G01D02*
X2518130Y916263D01*
G01D02*
X2518137Y916248D01*
G01X2516116Y933067D02*
X2516048Y933072D01*
G01D02*
X2515820Y933152D01*
G01D02*
X2515693Y933263D01*
G01D02*
X2515646Y933335D01*
G01D02*
X2515638Y933353D01*
G01X2511626Y933068D02*
X2511557Y933072D01*
G01D02*
X2511352Y933137D01*
G01D02*
X2511201Y933250D01*
G01D02*
X2511112Y933375D01*
G01D02*
X2511077Y933457D01*
G01D02*
X2511068Y933490D01*
G01D02*
X2511067Y933494D01*
G01X2519199Y933068D02*
X2519141Y933070D01*
G01D02*
X2518913Y933146D01*
G01D02*
X2518779Y933261D01*
G01D02*
X2518729Y933335D01*
G01D02*
X2518720Y933353D01*
G01X2513076Y933068D02*
X2513027Y933070D01*
G01D02*
X2512808Y933136D01*
G01D02*
X2512662Y933248D01*
G01D02*
X2512598Y933337D01*
G01D02*
X2512577Y933379D01*
G01D02*
X2512575Y933384D01*
G01X2517185Y916265D02*
X2517178Y916246D01*
G01D02*
X2517187Y916264D01*
G01D02*
X2517232Y916333D01*
G01D02*
X2517350Y916441D01*
G01D02*
X2517568Y916526D01*
G01D02*
X2517658Y916533D01*
G01X2514102Y916269D02*
X2514096Y916246D01*
G01D02*
X2514104Y916265D01*
G01D02*
X2514154Y916339D01*
G01D02*
X2514287Y916453D01*
G01D02*
X2514515Y916530D01*
G01D02*
X2514575Y916533D01*
G01X2519670Y933330D02*
X2519678Y933354D01*
G01D02*
X2519671Y933340D01*
G01D02*
X2519628Y933272D01*
G01D02*
X2519506Y933159D01*
G01D02*
X2519281Y933074D01*
G01D02*
X2519199Y933068D01*
G01X2516585Y933322D02*
X2516594Y933352D01*
G01D02*
X2516589Y933340D01*
G01D02*
X2516543Y933269D01*
G01D02*
X2516413Y933153D01*
G01D02*
X2516185Y933072D01*
G01D02*
X2516116Y933067D01*
G01X2511626Y934249D02*
X2511546Y934243D01*
G01D02*
X2511335Y934172D01*
G01D02*
X2511178Y934046D01*
G01D02*
X2511086Y933906D01*
G01D02*
X2511046Y933802D01*
G01D02*
X2511028Y933730D01*
G01D02*
X2511017Y933667D01*
G01D02*
X2511008Y933602D01*
G01D02*
X2511000Y933530D01*
G01X2513076Y934249D02*
X2512988Y934242D01*
G01D02*
X2512742Y934148D01*
G01D02*
X2512586Y934004D01*
G01D02*
X2512507Y933873D01*
G01D02*
X2512464Y933765D01*
G01D02*
X2512434Y933664D01*
G01D02*
X2512411Y933558D01*
G01D02*
X2512389Y933439D01*
G01D02*
X2512369Y933303D01*
G01D02*
X2512349Y933146D01*
G01D02*
X2512329Y932964D01*
G01D02*
X2512309Y932758D01*
G01D02*
X2512305Y932709D01*
G01X2519199Y934248D02*
X2519094Y934239D01*
G01D02*
X2518837Y934132D01*
G01D02*
X2518685Y933981D01*
G01D02*
X2518606Y933844D01*
G01D02*
X2518559Y933723D01*
G01D02*
X2518523Y933601D01*
G01D02*
X2518492Y933468D01*
G01D02*
X2518463Y933317D01*
G01D02*
X2518435Y933146D01*
G01D02*
X2518407Y932950D01*
G01D02*
X2518379Y932730D01*
G01D02*
X2518350Y932481D01*
G01D02*
X2518322Y932206D01*
G01D02*
X2518293Y931902D01*
G01D02*
X2518263Y931569D01*
G01D02*
X2518234Y931209D01*
G01D02*
X2518204Y930822D01*
G01D02*
X2518174Y930406D01*
G01D02*
X2518154Y930116D01*
G01X2516116Y934248D02*
X2516006Y934238D01*
G01D02*
X2515748Y934127D01*
G01D02*
X2515600Y933977D01*
G01D02*
X2515522Y933842D01*
G01D02*
X2515476Y933723D01*
G01D02*
X2515440Y933602D01*
G01D02*
X2515409Y933469D01*
G01D02*
X2515380Y933316D01*
G01D02*
X2515351Y933142D01*
G01D02*
X2515322Y932942D01*
G01D02*
X2515294Y932713D01*
G01D02*
X2515265Y932456D01*
G01D02*
X2515235Y932168D01*
G01D02*
X2515205Y931849D01*
G01D02*
X2515174Y931498D01*
G01D02*
X2515143Y931111D01*
G01D02*
X2515111Y930689D01*
G01D02*
X2515078Y930230D01*
G01D02*
X2515070Y930116D01*
G01X2512216Y915352D02*
X2512281Y915356D01*
G01D02*
X2512496Y915423D01*
G01D02*
X2512658Y915548D01*
G01D02*
X2512752Y915687D01*
G01D02*
X2512793Y915791D01*
G01D02*
X2512812Y915864D01*
G01D02*
X2512823Y915924D01*
G01D02*
X2512832Y915983D01*
G01D02*
X2512840Y916048D01*
G01D02*
X2512847Y916121D01*
G01D02*
X2512854Y916204D01*
G01D02*
X2512862Y916298D01*
G01X2517658Y915352D02*
X2517740Y915358D01*
G01D02*
X2517996Y915454D01*
G01D02*
X2518159Y915604D01*
G01D02*
X2518243Y915742D01*
G01D02*
X2518293Y915862D01*
G01D02*
X2518329Y915982D01*
G01D02*
X2518361Y916115D01*
G01D02*
X2518391Y916266D01*
G01D02*
X2518419Y916438D01*
G01D02*
X2518448Y916633D01*
G01D02*
X2518476Y916856D01*
G01D02*
X2518505Y917107D01*
G01D02*
X2518535Y917389D01*
G01D02*
X2518565Y917704D01*
G01D02*
X2518595Y918053D01*
G01D02*
X2518627Y918438D01*
G01D02*
X2518659Y918862D01*
G01D02*
X2518693Y919328D01*
G01D02*
X2518704Y919486D01*
G01X2514574Y915352D02*
X2514664Y915359D01*
G01D02*
X2514922Y915459D01*
G01D02*
X2515077Y915606D01*
G01D02*
X2515158Y915739D01*
G01D02*
X2515206Y915854D01*
G01D02*
X2515242Y915967D01*
G01D02*
X2515272Y916091D01*
G01D02*
X2515301Y916230D01*
G01D02*
X2515329Y916388D01*
G01D02*
X2515356Y916567D01*
G01D02*
X2515383Y916771D01*
G01D02*
X2515411Y917001D01*
G01D02*
X2515439Y917259D01*
G01D02*
X2515467Y917544D01*
G01D02*
X2515495Y917859D01*
G01D02*
X2515524Y918202D01*
G01D02*
X2515554Y918574D01*
G01D02*
X2515585Y918978D01*
G01D02*
X2515620Y919486D01*
G01X2513581Y933391D02*
Y933390D01*
G01D02*
X2513564Y933351D01*
G01D02*
X2513504Y933262D01*
G01D02*
X2513364Y933146D01*
G01D02*
X2513144Y933072D01*
G01D02*
X2513076Y933068D01*
G01X2514608Y1385233D02*
Y1400833D01*
X2512268Y1397713D01*
G01Y1385233D02*
X2516948D01*
G01X2528218Y1388353D02*
X2529388Y1386533D01*
X2530948Y1385493D01*
X2532703Y1385233D01*
X2534263Y1385493D01*
X2535823Y1386793D01*
X2536798Y1388353D01*
X2536993Y1389913D01*
X2536603Y1391733D01*
X2535238Y1393033D01*
X2533873Y1393553D01*
X2532118D01*
G01X2533873D02*
X2535043Y1394333D01*
X2536018Y1395633D01*
X2536408Y1397193D01*
X2536018Y1398753D01*
X2535043Y1400053D01*
X2533288Y1400833D01*
X2531533Y1400573D01*
X2529778Y1399533D01*
G01X2539941Y-156392D02*
Y-280554D01*
G01X2536004Y-284491D02*
G03X2539941Y-280554I0J3937D01*
G01X2536004Y-152455D02*
X2524193D01*
G01X2520256Y-148518D02*
Y28356D01*
G01X2539941Y-156392D02*
G03X2536004Y-152455I-3937J0D01*
G01X2520256Y-148518D02*
G03X2524193Y-152455I3937J0D01*
G01X2536004Y32293D02*
X2524193D01*
G01X2539941Y59269D02*
Y36230D01*
G01X2524193Y32293D02*
G03X2520256Y28356I0J-3937D01*
G01X2536004Y32293D02*
G03X2539941Y36230I0J3937D01*
G01X2529122Y94714D02*
X2538188Y100758D01*
G01Y62544D02*
X2529122Y68588D01*
G01X2539941Y59269D02*
G03X2538188Y62544I-3937J-1D01*
G01X2529122Y68588D02*
G03X2526938Y69250I-2185J-3275D01*
G01Y94053D02*
G03X2529122Y94714I0J3937D01*
G01X2538188Y100758D02*
G03X2539941Y104034I-2184J3276D01*
G01D02*
Y184013D01*
G01D02*
G03X2536004Y187950I-3937J0D01*
G01X2523809Y238695D02*
Y244469D01*
G01Y243025D02*
X2524243Y243747D01*
X2524892Y244325D01*
X2525758Y244469D01*
X2526516Y244325D01*
X2527166Y243747D01*
X2527491Y242737D01*
Y238695D01*
G01X2538497D02*
Y247356D01*
X2534491Y241149D01*
X2539905D01*
G01X2545859Y238406D02*
X2545642Y238551D01*
Y238839D01*
X2545859Y238984D01*
X2546076Y238839D01*
Y238551D01*
X2545859Y238406D01*
G01X2554520Y247356D02*
X2553654Y247067D01*
X2553004Y246346D01*
X2552571Y245480D01*
X2552246Y244325D01*
X2552138Y243025D01*
X2552246Y241726D01*
X2552571Y240571D01*
X2553004Y239705D01*
X2553654Y238984D01*
X2554520Y238695D01*
X2555386Y238984D01*
X2556036Y239705D01*
X2556469Y240571D01*
X2556794Y241726D01*
X2556902Y243025D01*
X2556794Y244325D01*
X2556469Y245480D01*
X2556036Y246346D01*
X2555386Y247067D01*
X2554520Y247356D01*
G01X2563181D02*
X2562315Y247067D01*
X2561665Y246346D01*
X2561232Y245480D01*
X2560907Y244325D01*
X2560799Y243025D01*
X2560907Y241726D01*
X2561232Y240571D01*
X2561665Y239705D01*
X2562315Y238984D01*
X2563181Y238695D01*
X2564047Y238984D01*
X2564697Y239705D01*
X2565130Y240571D01*
X2565455Y241726D01*
X2565563Y243025D01*
X2565455Y244325D01*
X2565130Y245480D01*
X2564697Y246346D01*
X2564047Y247067D01*
X2563181Y247356D01*
G01X2574875Y238695D02*
Y247356D01*
X2577473D01*
X2578339Y246923D01*
X2578989Y245913D01*
X2579205Y244758D01*
X2578989Y243603D01*
X2578447Y242737D01*
X2577473Y242304D01*
X2574875D01*
G01X2585701Y247356D02*
Y238695D01*
G01X2583211Y247356D02*
X2588191D01*
G01X2592088Y238695D02*
Y247356D01*
G01X2596636D02*
Y238695D01*
G01Y243025D02*
X2592088D01*
G01X2546394Y396840D02*
X2537733D01*
X2539465Y395541D01*
G01X2546394D02*
Y398139D01*
G01X2542785Y403444D02*
X2541775Y404202D01*
X2541197Y404851D01*
X2540909Y405718D01*
X2541197Y406475D01*
X2541775Y407017D01*
X2542641Y407450D01*
X2543651Y407558D01*
X2544518Y407450D01*
X2545384Y407017D01*
X2546105Y406367D01*
X2546394Y405609D01*
X2546105Y404743D01*
X2545239Y403985D01*
X2543940Y403552D01*
X2542497Y403444D01*
X2540620Y403660D01*
X2539609Y403985D01*
X2538599Y404527D01*
X2537877Y405284D01*
X2537733Y406042D01*
X2538022Y406800D01*
X2538743Y407342D01*
G01X2539176Y412105D02*
X2538311Y412755D01*
X2537877Y413512D01*
X2537733Y414379D01*
X2538022Y415461D01*
X2538743Y416219D01*
X2539609Y416436D01*
X2540476Y416327D01*
X2541197Y415894D01*
X2542641Y413729D01*
X2543651Y412755D01*
X2545095Y412105D01*
X2546394Y411888D01*
Y416436D01*
G01X2546683Y422823D02*
X2546538Y422606D01*
X2546250D01*
X2546105Y422823D01*
X2546250Y423040D01*
X2546538D01*
X2546683Y422823D01*
G01X2542785Y429427D02*
X2541775Y430185D01*
X2541197Y430834D01*
X2540909Y431701D01*
X2541197Y432458D01*
X2541775Y433000D01*
X2542641Y433433D01*
X2543651Y433541D01*
X2544518Y433433D01*
X2545384Y433000D01*
X2546105Y432350D01*
X2546394Y431592D01*
X2546105Y430726D01*
X2545239Y429968D01*
X2543940Y429535D01*
X2542497Y429427D01*
X2540620Y429643D01*
X2539609Y429968D01*
X2538599Y430510D01*
X2537877Y431267D01*
X2537733Y432025D01*
X2538022Y432783D01*
X2538743Y433325D01*
G01X2542785Y438088D02*
X2541775Y438846D01*
X2541197Y439495D01*
X2540909Y440362D01*
X2541197Y441119D01*
X2541775Y441661D01*
X2542641Y442094D01*
X2543651Y442202D01*
X2544518Y442094D01*
X2545384Y441661D01*
X2546105Y441011D01*
X2546394Y440253D01*
X2546105Y439387D01*
X2545239Y438629D01*
X2543940Y438196D01*
X2542497Y438088D01*
X2540620Y438304D01*
X2539609Y438629D01*
X2538599Y439171D01*
X2537877Y439928D01*
X2537733Y440686D01*
X2538022Y441444D01*
X2538743Y441986D01*
G01X2548559Y619828D02*
Y495667D01*
G01X2544622Y491730D02*
G03X2548559Y495667I0J3937D01*
G01Y876317D02*
Y447724D01*
G01X2542692Y564735D02*
X2542733Y564743D01*
G01X2541079Y563383D02*
X2542097D01*
G01X2543211D02*
X2544229D01*
G01Y564368D02*
X2541079D01*
G01Y564464D02*
X2544229D01*
G01X2542511Y564525D02*
X2542462D01*
G01X2542930D02*
X2542733D01*
G01X2542724Y564567D02*
X2542880D01*
G01Y564693D02*
X2542724D01*
G01X2542733Y564743D02*
X2542880D01*
G01X2541079Y564856D02*
X2544229D01*
G01X2542462Y564919D02*
X2542511D01*
G01X2542880D02*
X2542930D01*
G01X2541276Y564958D02*
X2544032D01*
G01X2543441Y566927D02*
X2541867D01*
G01X2541276Y568108D02*
X2541867D01*
G01X2543441D02*
X2544032D01*
G01X2544229Y568210D02*
X2541079D01*
G01X2544229Y568602D02*
X2541079D01*
G01X2544229Y568698D02*
X2541079D01*
G01X2544229Y569683D02*
X2543211D01*
G01X2542097D02*
X2541079D01*
G01X2542733Y564525D02*
X2542692Y564533D01*
G01X2542700Y564575D02*
X2542724Y564567D01*
G01X2542692Y564533D02*
X2542659Y564559D01*
G01X2542683Y564592D02*
X2542700Y564575D01*
G01X2542659Y564559D02*
X2542634Y564592D01*
G01X2542724Y564693D02*
X2542700Y564684D01*
G01X2542634Y564592D02*
X2542626Y564617D01*
G01X2542675D02*
X2542683Y564592D01*
G01X2528874Y818639D02*
Y613639D01*
G01D02*
Y612143D01*
G01X2530874Y631639D02*
Y613639D01*
G01X2541079Y563383D02*
Y569683D01*
G01X2541276D02*
Y568108D01*
G01Y563383D02*
Y564958D01*
G01X2541867Y566927D02*
Y568108D01*
G01X2542462Y564525D02*
Y564919D01*
G01X2542511D02*
Y564592D01*
G01X2542561Y564651D02*
Y564584D01*
G01X2542626Y564617D02*
Y564651D01*
G01X2542675Y564643D02*
Y564617D01*
G01X2542880Y564567D02*
Y564693D01*
G01Y564743D02*
Y564919D01*
G01X2542930D02*
Y564525D01*
G01X2543441Y568108D02*
Y566927D01*
G01X2544032Y564958D02*
Y563383D01*
G01Y568108D02*
Y569683D01*
G01X2544229Y563383D02*
Y569683D01*
G01X2542659Y564709D02*
X2542692Y564735D01*
G01X2542626Y564651D02*
X2542634Y564676D01*
G01X2542683Y564668D02*
X2542675Y564643D01*
G01X2542634Y564676D02*
X2542659Y564709D01*
G01X2542511Y564592D02*
X2542561Y564651D01*
G01Y564584D02*
X2542511Y564525D01*
G01X2542700Y564684D02*
X2542683Y564668D01*
G01X2542097Y569683D02*
G03X2543211I557J196D01*
G01Y563383D02*
G03X2542097I-557J-196D01*
G01X2544622Y623765D02*
X2532811D01*
G01X2552369Y629639D02*
X2555269D01*
G01X2569374Y631639D02*
X2559030D01*
G01X2552722D02*
X2530874D01*
G01X2552722D02*
X2559030D01*
G01X2536874Y635139D02*
X2569374D01*
G01X2530874Y637639D02*
X2553498D01*
G01X2569374Y641139D02*
X2536874D01*
G01X2538874Y646139D02*
X2536874D01*
G01Y653289D02*
X2568374D01*
G01Y654989D02*
X2536874D01*
G01Y662289D02*
X2568374D01*
G01Y663989D02*
X2536874D01*
G01Y673289D02*
X2568374D01*
G01X2569374Y637139D02*
X2555269Y629639D01*
G01X2530874Y790139D02*
Y642139D01*
G01Y637639D02*
Y631639D01*
G01Y642139D02*
Y637639D01*
G01X2536874Y635139D02*
Y797139D01*
G01X2538874Y646139D02*
Y635139D01*
G01X2553498Y637639D02*
Y636039D01*
G01X2568374Y653289D02*
Y654989D01*
G01Y662289D02*
Y663989D01*
G01Y673289D02*
Y674989D01*
G01X2569374Y800639D02*
Y631639D01*
G01X2552369Y629639D02*
X2553498Y636039D01*
G01X2528874Y627702D02*
G03X2530841Y624294I3937J1D01*
G01X2548559Y619828D02*
G03X2544622Y623765I-3937J0D01*
G01X2530874Y624275D02*
G03X2532811Y623765I1938J3427D01*
G01X2530841Y624294D02*
G03X2530874Y624275I1981J3402D01*
G01X2568374Y674989D02*
X2536874D01*
G01Y682289D02*
X2568374D01*
G01Y683989D02*
X2536874D01*
G01X2569374Y691139D02*
X2536874D01*
G01Y694839D02*
X2563874D01*
G01X2536874Y697439D02*
X2563874D01*
G01X2536874Y704839D02*
X2563874D01*
G01X2536874Y707439D02*
X2563874D01*
G01X2536874Y714839D02*
X2563874D01*
G01X2536874Y717439D02*
X2563874D01*
G01X2536874Y724839D02*
X2563874D01*
G01X2536874Y727439D02*
X2563874D01*
G01Y694839D02*
Y697439D01*
G01Y704839D02*
Y707439D01*
G01Y714839D02*
Y717439D01*
G01Y724839D02*
Y727439D01*
G01X2568374Y682289D02*
Y683989D01*
G01X2536874Y734839D02*
X2563874D01*
G01X2536874Y737439D02*
X2563874D01*
G01X2569374Y741139D02*
X2536874D01*
G01Y748289D02*
X2568374D01*
G01Y749989D02*
X2536874D01*
G01Y757289D02*
X2568374D01*
G01Y758989D02*
X2536874D01*
G01Y768289D02*
X2568374D01*
G01Y769989D02*
X2536874D01*
G01Y777289D02*
X2568374D01*
G01Y778989D02*
X2536874D01*
G01X2538874Y786139D02*
X2536874D01*
G01X2538874Y797139D02*
Y786139D01*
G01X2563874Y734839D02*
Y737439D01*
G01X2568374Y748289D02*
Y749989D01*
G01Y757289D02*
Y758989D01*
G01Y768289D02*
Y769989D01*
G01Y777289D02*
Y778989D01*
G01X2536874Y791139D02*
X2569374D01*
G01X2553498Y794639D02*
X2530874D01*
G01X2569374Y797139D02*
X2536874D01*
G01X2559030Y800639D02*
X2552722D01*
G01D02*
X2530874D01*
G01X2559030D02*
X2569374D01*
G01X2555269Y802639D02*
X2552369D01*
G01X2544622Y808513D02*
X2532811D01*
G01X2528166Y841139D02*
X2523835D01*
G01X2555269Y802639D02*
X2569374Y795139D01*
G01X2546806Y838765D02*
X2537740Y844809D01*
G01X2523835Y841139D02*
Y829919D01*
G01X2528166D02*
Y841139D01*
G01X2528874Y844092D02*
Y829919D01*
G01Y820135D02*
Y818639D01*
G01X2530874Y800639D02*
Y794639D01*
G01D02*
Y790139D01*
G01Y800639D02*
Y818639D01*
G01X2532811Y825982D02*
Y848029D01*
G01X2548559Y835489D02*
Y812450D01*
G01X2553498Y796239D02*
Y794639D01*
G01Y796239D02*
X2552369Y802639D01*
G01X2530841Y807985D02*
G03X2528874Y804576I1970J-3409D01*
G01X2532811Y808513D02*
G03X2530874Y808004I-1J-3937D01*
G01X2544622Y808513D02*
G03X2548559Y812450I0J3937D01*
G01Y835489D02*
G03X2546806Y838765I-3937J0D01*
G01X2537740Y844809D02*
G03X2535556Y845470I-2184J-3276D01*
G01X2530874Y808004D02*
G03X2530841Y807985I1948J-3421D01*
G01X2539493Y845470D02*
X2589985D01*
G01X2537740Y870934D02*
X2546806Y876978D01*
G01X2528166Y884840D02*
X2523835D01*
G01D02*
Y873620D01*
G01X2528166D02*
Y884840D01*
G01X2528874Y887793D02*
Y873620D01*
G01X2532811Y869683D02*
Y891730D01*
G01X2548559Y880254D02*
Y912778D01*
G01X2535556Y870273D02*
G03X2537740Y870934I0J3937D01*
G01X2546806Y876978D02*
G03X2548559Y880254I-2184J3276D01*
G01X2539493Y870273D02*
X2589985D01*
G01X2529480Y915353D02*
X2529532Y915356D01*
G01X2562326Y912987D02*
X2536552Y912596D01*
G01X2529465Y915352D02*
X2529480D01*
G01X2529465Y916533D02*
X2529452D01*
G01X2523824Y915352D02*
X2523825D01*
G01X2526908Y915353D02*
X2526909D01*
G01X2532811Y915943D02*
X2531237D01*
G01Y917911D02*
X2532811D01*
G01Y918241D02*
X2531237D01*
G01X2532811Y919289D02*
X2531237D01*
G01X2536552Y919486D02*
X2532811D01*
G01X2531063D02*
X2530843D01*
G01X2531237D02*
X2531063D01*
G01X2527044D02*
X2525862D01*
G01X2527890D02*
X2527044D01*
G01X2523960D02*
X2522778D01*
G01X2525862D02*
X2523960D01*
G01X2522778D02*
X2520877D01*
G01X2531237D02*
X2532811D01*
G01Y920864D02*
X2531237D01*
G01X2532811Y921061D02*
X2529842D01*
G01D02*
X2529786D01*
G01D02*
X2528605D01*
G01D02*
X2527890D01*
G01X2532811Y922832D02*
X2531237D01*
G01X2530983D02*
X2529802D01*
G01X2531237D02*
X2530983D01*
G01X2529802D02*
X2529724D01*
G01D02*
X2528543D01*
G01D02*
X2526906D01*
G01X2532811Y923029D02*
X2530449D01*
G01Y926572D02*
X2532811D01*
G01Y926769D02*
X2531237D01*
G01X2526906D02*
X2528397D01*
G01D02*
X2529578D01*
G01D02*
X2529718D01*
G01D02*
X2530899D01*
G01D02*
X2531237D01*
G01X2532811Y928541D02*
X2529678D01*
G01X2529503D02*
X2528322D01*
G01X2529678D02*
X2529503D01*
G01X2528322D02*
X2527890D01*
G01X2532811Y928738D02*
X2531237D01*
G01X2529484Y916533D02*
X2529465D01*
G01X2530659D02*
X2530646D01*
G01X2529443Y915353D02*
X2529465Y915352D01*
G01X2530631Y915353D02*
X2530646Y915352D01*
G01X2520245Y930116D02*
X2522146D01*
G01D02*
X2523329D01*
G01D02*
X2525230D01*
G01D02*
X2526412D01*
G01D02*
X2527890D01*
G01X2531237D02*
X2532811D01*
G01X2530843D02*
X2531237D01*
G01X2532811D02*
X2536552D01*
G01X2532811Y930313D02*
X2531237D01*
G01Y931360D02*
X2532811D01*
G01Y931691D02*
X2531237D01*
G01Y933659D02*
X2532811D01*
G01X2525365Y934249D02*
X2525366D01*
G01X2562326Y936615D02*
X2536552Y937006D01*
G01X2530570Y915357D02*
X2530631Y915353D01*
G01X2529389Y915357D02*
X2529443Y915353D01*
G01X2527700Y933239D02*
Y933240D01*
G01X2528867Y933071D02*
Y933070D01*
G01X2521484Y916325D02*
X2521485Y916326D01*
G01X2520319Y916502D02*
Y916501D01*
G01X2526906Y922832D02*
Y926769D01*
G01X2527890Y930116D02*
Y928541D01*
G01Y919486D02*
Y921061D01*
G01X2530449Y923029D02*
Y926572D01*
G01X2530843Y921061D02*
Y919486D01*
G01Y928541D02*
Y929230D01*
G01D02*
Y930116D01*
G01X2531237Y933659D02*
Y915943D01*
G01X2529222Y927239D02*
X2529122Y922570D01*
G01X2530296Y922257D02*
X2530393Y926769D01*
G01D02*
X2530413Y927674D01*
G01X2529122Y922570D02*
X2529103Y921728D01*
G01X2529243Y928151D02*
X2529222Y927239D01*
G01X2530279Y921481D02*
X2530296Y922257D01*
G01X2529103Y921728D02*
X2529085Y920938D01*
G01X2530413Y927674D02*
X2530433Y928541D01*
G01D02*
X2530447Y929146D01*
G01X2530253Y920395D02*
X2530279Y921481D01*
G01X2530447Y929146D02*
X2530464Y929799D01*
G01X2529335Y931619D02*
X2529322Y931203D01*
G01X2528263Y924672D02*
X2528343Y926123D01*
G01D02*
X2528390Y926946D01*
G01X2526775Y923947D02*
X2526661Y926000D01*
G01X2528654Y919713D02*
X2528678Y919080D01*
G01X2529858Y919122D02*
X2529833Y919767D01*
G01X2529660Y924601D02*
X2529626Y925512D01*
G01X2528629Y920402D02*
X2528654Y919713D01*
G01X2529833Y919767D02*
X2529808Y920466D01*
G01X2528464Y925009D02*
X2528498Y924093D01*
G01X2529808Y920466D02*
X2529781Y921217D01*
G01X2529693Y923711D02*
X2529660Y924601D01*
G01X2531076Y918996D02*
X2531063Y919481D01*
G01D02*
X2531050Y919988D01*
G01X2530843Y929230D02*
X2530820Y930115D01*
G01X2529857Y920440D02*
X2529874Y919747D01*
G01X2529648Y929777D02*
X2529666Y929056D01*
G01X2531050Y919988D02*
X2531031Y920717D01*
G01X2530862Y928429D02*
X2530843Y929230D01*
G01X2529666Y929056D02*
X2529685Y928263D01*
G01X2531031Y920717D02*
X2531013Y921489D01*
G01X2529830Y921581D02*
X2529857Y920440D01*
G01X2530879Y927677D02*
X2530862Y928429D01*
G01X2529685Y928263D02*
X2529704Y927409D01*
G01X2531013Y921489D02*
X2530995Y922296D01*
G01X2529812Y922406D02*
X2529830Y921581D01*
G01X2529704Y927409D02*
X2529724Y926511D01*
G01X2530906Y926485D02*
X2530879Y927677D01*
G01X2530995Y922296D02*
X2530977Y923127D01*
G01X2529783Y923728D02*
X2529812Y922406D01*
G01X2532811Y915943D02*
Y933659D01*
G01X2536552Y937006D02*
Y912596D01*
G01X2548559Y912778D02*
Y936824D01*
G01D02*
Y960234D01*
G01X2562326Y912987D02*
Y936615D01*
G01X2562652Y913167D02*
Y936434D01*
G01X2520496Y916509D02*
G03X2520502Y916452I22433J2333D01*
G01X2523596Y916352D02*
G03X2523603Y916297I17675J2222D01*
G01X2562652Y913167D02*
G03Y936434I-18029J11633D01*
G01X2562326Y912987D02*
G03X2562652Y913167I-5J394D01*
G01Y936434D02*
G03X2562326Y936615I-331J-213D01*
G01X2527911Y928558D02*
G03X2527798Y926778I305934J-20315D01*
G01X2528023Y930134D02*
G03X2527911Y928558I134538J-10353D01*
G01X2529849Y928557D02*
G03X2529806Y926778I789175J-19965D01*
G01Y926779D02*
X2529760Y924801D01*
G01D02*
X2529719Y922969D01*
G01D02*
X2529715Y922822D01*
G01X2530150Y933076D02*
X2530151Y933060D01*
G01X2530051Y915861D02*
X2530070Y915790D01*
G01D02*
X2530109Y915691D01*
G01D02*
X2530199Y915555D01*
G01D02*
X2530357Y915428D01*
G01D02*
X2530570Y915357D01*
G01X2527955Y933371D02*
X2527958Y933361D01*
G01D02*
X2527968Y933320D01*
G01D02*
X2527982Y933252D01*
G01D02*
X2527998Y933161D01*
G01D02*
X2528016Y933049D01*
G01D02*
X2528033Y932917D01*
G01D02*
X2528052Y932763D01*
G01D02*
X2528071Y932588D01*
G01D02*
X2528090Y932391D01*
G01X2524303Y916248D02*
X2524293Y916281D01*
G01D02*
X2524276Y916348D01*
G01D02*
X2524256Y916446D01*
G01D02*
X2524235Y916572D01*
G01D02*
X2524211Y916726D01*
G01D02*
X2524187Y916908D01*
G01D02*
X2524162Y917117D01*
G01D02*
X2524136Y917352D01*
G01D02*
X2524110Y917615D01*
G01D02*
X2524083Y917904D01*
G01D02*
X2524056Y918218D01*
G01D02*
X2524029Y918559D01*
G01D02*
X2524000Y918927D01*
G01D02*
X2523972Y919321D01*
G01X2527386Y916249D02*
X2527377Y916281D01*
G01D02*
X2527360Y916349D01*
G01D02*
X2527339Y916450D01*
G01D02*
X2527317Y916583D01*
G01D02*
X2527292Y916748D01*
G01D02*
X2527266Y916944D01*
G01D02*
X2527239Y917172D01*
G01D02*
X2527212Y917433D01*
G01D02*
X2527183Y917727D01*
G01D02*
X2527154Y918054D01*
G01D02*
X2527124Y918414D01*
G01D02*
X2527093Y918809D01*
G01D02*
X2527061Y919240D01*
G01X2521219Y916249D02*
X2521210Y916280D01*
G01D02*
X2521193Y916346D01*
G01D02*
X2521174Y916443D01*
G01D02*
X2521152Y916570D01*
G01D02*
X2521128Y916724D01*
G01D02*
X2521104Y916907D01*
G01D02*
X2521079Y917118D01*
G01X2521804Y933353D02*
X2521812Y933328D01*
G01D02*
X2521828Y933266D01*
G01D02*
X2521847Y933174D01*
G01D02*
X2521869Y933052D01*
G01D02*
X2521891Y932903D01*
G01D02*
X2521915Y932726D01*
G01D02*
X2521941Y932522D01*
G01D02*
X2521966Y932291D01*
G01D02*
X2521992Y932033D01*
G01D02*
X2522019Y931746D01*
G01D02*
X2522046Y931433D01*
G01D02*
X2522074Y931091D01*
G01D02*
X2522103Y930721D01*
G01D02*
X2522132Y930323D01*
G01X2524887Y933354D02*
X2524894Y933333D01*
G01D02*
X2524908Y933280D01*
G01D02*
X2524926Y933199D01*
G01D02*
X2524945Y933092D01*
G01D02*
X2524967Y932961D01*
G01D02*
X2524989Y932806D01*
G01D02*
X2525011Y932627D01*
G01D02*
X2525035Y932425D01*
G01D02*
X2525059Y932199D01*
G01D02*
X2525084Y931950D01*
G01D02*
X2525109Y931678D01*
G01D02*
X2525134Y931381D01*
G01D02*
X2525160Y931061D01*
G01D02*
X2525187Y930718D01*
G01D02*
X2525214Y930350D01*
G01X2530022Y916115D02*
X2530019Y916135D01*
G01D02*
X2530014Y916172D01*
G01D02*
X2530008Y916223D01*
G01D02*
X2530002Y916288D01*
G01D02*
X2530001Y916300D01*
G01X2529496Y933495D02*
X2529499Y933478D01*
G01D02*
X2529504Y933444D01*
G01D02*
X2529508Y933398D01*
G01D02*
X2529514Y933338D01*
G01D02*
X2529520Y933265D01*
G01D02*
X2529526Y933179D01*
G01D02*
X2529533Y933080D01*
G01D02*
X2529539Y932966D01*
G01D02*
X2529546Y932838D01*
G01D02*
X2529553Y932696D01*
G01D02*
X2529560Y932538D01*
G01D02*
X2529568Y932366D01*
G01D02*
X2529575Y932178D01*
G01D02*
X2529583Y931975D01*
G01D02*
X2529590Y931756D01*
G01D02*
X2529598Y931522D01*
G01D02*
X2529606Y931273D01*
G01D02*
X2529614Y931007D01*
G01D02*
X2529622Y930726D01*
G01D02*
X2529631Y930427D01*
G01D02*
X2529639Y930111D01*
G01D02*
X2529648Y929777D01*
G01X2530977Y923127D02*
X2530941Y924819D01*
G01D02*
X2530906Y926485D01*
G01X2529724Y926511D02*
X2529763Y924650D01*
G01D02*
X2529783Y923728D01*
G01X2529874Y919747D02*
X2529883Y919422D01*
G01D02*
X2529891Y919111D01*
G01D02*
X2529900Y918815D01*
G01D02*
X2529908Y918533D01*
G01D02*
X2529916Y918265D01*
G01D02*
X2529924Y918013D01*
G01D02*
X2529932Y917774D01*
G01D02*
X2529940Y917551D01*
G01D02*
X2529948Y917343D01*
G01D02*
X2529956Y917149D01*
G01D02*
X2529964Y916971D01*
G01D02*
X2529971Y916807D01*
G01D02*
X2529979Y916659D01*
G01D02*
X2529986Y916525D01*
G01D02*
X2529993Y916406D01*
G01D02*
X2530001Y916299D01*
G01X2530820Y930115D02*
X2530813Y930415D01*
G01D02*
X2530804Y930702D01*
G01D02*
X2530796Y930976D01*
G01D02*
X2530789Y931236D01*
G01D02*
X2530781Y931483D01*
G01D02*
X2530773Y931716D01*
G01D02*
X2530766Y931935D01*
G01D02*
X2530758Y932141D01*
G01D02*
X2530751Y932333D01*
G01D02*
X2530743Y932511D01*
G01D02*
X2530736Y932677D01*
G01D02*
X2530729Y932830D01*
G01D02*
X2530722Y932969D01*
G01D02*
X2530714Y933096D01*
G01D02*
X2530707Y933211D01*
G01D02*
X2530700Y933315D01*
G01X2531118Y917656D02*
X2531110Y917890D01*
G01D02*
X2531102Y918142D01*
G01D02*
X2531093Y918410D01*
G01D02*
X2531085Y918695D01*
G01D02*
X2531076Y918996D01*
G01X2529781Y921217D02*
X2529752Y922012D01*
G01D02*
X2529738Y922424D01*
G01D02*
X2529693Y923711D01*
G01X2528544Y922769D02*
X2528574Y921933D01*
G01D02*
X2528629Y920402D01*
G01X2528498Y924093D02*
X2528529Y923202D01*
G01D02*
X2528544Y922769D01*
G01X2529626Y925512D02*
X2529609Y925975D01*
G01D02*
X2529591Y926440D01*
G01D02*
X2529572Y926908D01*
G01D02*
X2529553Y927378D01*
G01D02*
X2529533Y927848D01*
G01D02*
X2529513Y928317D01*
G01X2528678Y919080D02*
X2528690Y918785D01*
G01D02*
X2528701Y918504D01*
G01D02*
X2528712Y918238D01*
G01D02*
X2528723Y917987D01*
G01D02*
X2528733Y917751D01*
G01D02*
X2528744Y917529D01*
G01D02*
X2528754Y917322D01*
G01D02*
X2528763Y917131D01*
G01D02*
X2528773Y916954D01*
G01D02*
X2528782Y916793D01*
G01D02*
X2528791Y916646D01*
G01D02*
X2528800Y916513D01*
G01D02*
X2528808Y916395D01*
G01D02*
X2528817Y916290D01*
G01X2528315Y928682D02*
X2528335Y928240D01*
G01D02*
X2528355Y927789D01*
G01D02*
X2528374Y927332D01*
G01D02*
X2528393Y926870D01*
G01D02*
X2528411Y926406D01*
G01D02*
X2528429Y925940D01*
G01D02*
X2528447Y925474D01*
G01D02*
X2528464Y925009D01*
G01X2529513Y928317D02*
X2529492Y928783D01*
G01D02*
X2529470Y929246D01*
G01D02*
X2529448Y929702D01*
G01D02*
X2529425Y930144D01*
G01D02*
X2529401Y930567D01*
G01D02*
X2529378Y930967D01*
G01D02*
X2529354Y931338D01*
G01D02*
X2529331Y931678D01*
G01D02*
X2529308Y931987D01*
G01D02*
X2529285Y932265D01*
G01D02*
X2529263Y932515D01*
G01D02*
X2529241Y932739D01*
G01D02*
X2529219Y932938D01*
G01D02*
X2529197Y933115D01*
G01D02*
X2529175Y933274D01*
G01D02*
X2529152Y933415D01*
G01D02*
X2529127Y933541D01*
G01D02*
X2529100Y933654D01*
G01D02*
X2529067Y933760D01*
G01D02*
X2529021Y933872D01*
G01D02*
X2528938Y934005D01*
G01D02*
X2528778Y934151D01*
G01D02*
X2528524Y934244D01*
G01D02*
X2528445Y934250D01*
G01X2525476Y926066D02*
X2525541Y924905D01*
G01D02*
X2525609Y923681D01*
G01X2523722Y923398D02*
X2523652Y924659D01*
G01D02*
X2523578Y925984D01*
G01X2522388Y926146D02*
X2522461Y924831D01*
G01D02*
X2522536Y923490D01*
G01X2525609Y923681D02*
X2525644Y923051D01*
G01D02*
X2525680Y922416D01*
G01D02*
X2525717Y921786D01*
G01D02*
X2525754Y921173D01*
G01D02*
X2525790Y920585D01*
G01D02*
X2525825Y920031D01*
G01D02*
X2525860Y919517D01*
G01X2523578Y925984D02*
X2523541Y926648D01*
G01D02*
X2523504Y927297D01*
G01D02*
X2523467Y927923D01*
G01D02*
X2523432Y928516D01*
G01D02*
X2523397Y929071D01*
G01D02*
X2523364Y929590D01*
G01D02*
X2523331Y930072D01*
G01X2526661Y926000D02*
X2526624Y926659D01*
G01D02*
X2526587Y927297D01*
G01D02*
X2526552Y927911D01*
G01D02*
X2526517Y928496D01*
G01D02*
X2526482Y929051D01*
G01D02*
X2526449Y929574D01*
G01D02*
X2526416Y930063D01*
G01X2522536Y923490D02*
X2522572Y922836D01*
G01D02*
X2522609Y922207D01*
G01D02*
X2522644Y921610D01*
G01D02*
X2522678Y921048D01*
G01D02*
X2522710Y920519D01*
G01D02*
X2522742Y920022D01*
G01D02*
X2522773Y919556D01*
G01X2526851Y922592D02*
X2526813Y923262D01*
G01D02*
X2526775Y923947D01*
G01X2519894Y917104D02*
X2519922Y916853D01*
G01D02*
X2519951Y916631D01*
G01D02*
X2519979Y916436D01*
G01D02*
X2520007Y916266D01*
G01D02*
X2520037Y916119D01*
G01D02*
X2520068Y915989D01*
G01D02*
X2520104Y915870D01*
G01D02*
X2520151Y915753D01*
G01D02*
X2520229Y915620D01*
G01D02*
X2520378Y915471D01*
G01D02*
X2520633Y915363D01*
G01D02*
X2520741Y915353D01*
G01X2520887Y919343D02*
X2520857Y919768D01*
G01D02*
X2520828Y920220D01*
G01D02*
X2520797Y920696D01*
G01D02*
X2520766Y921198D01*
G01D02*
X2520735Y921726D01*
G01D02*
X2520702Y922276D01*
G01D02*
X2520670Y922851D01*
G01D02*
X2520636Y923449D01*
G01X2523972Y919321D02*
X2523943Y919741D01*
G01D02*
X2523913Y920188D01*
G01D02*
X2523883Y920661D01*
G01D02*
X2523852Y921158D01*
G01D02*
X2523821Y921681D01*
G01D02*
X2523789Y922229D01*
G01D02*
X2523756Y922801D01*
G01D02*
X2523722Y923398D01*
G01X2522132Y930323D02*
X2522161Y929899D01*
G01D02*
X2522191Y929447D01*
G01D02*
X2522222Y928969D01*
G01D02*
X2522254Y928462D01*
G01D02*
X2522286Y927927D01*
G01D02*
X2522319Y927363D01*
G01D02*
X2522353Y926769D01*
G01D02*
X2522388Y926146D01*
G01X2527061Y919240D02*
X2527029Y919706D01*
G01D02*
X2526995Y920210D01*
G01D02*
X2526961Y920751D01*
G01D02*
X2526926Y921330D01*
G01D02*
X2526889Y921945D01*
G01D02*
X2526851Y922592D01*
G01X2525214Y930350D02*
X2525241Y929959D01*
G01D02*
X2525269Y929545D01*
G01D02*
X2525297Y929109D01*
G01D02*
X2525326Y928651D01*
G01D02*
X2525355Y928172D01*
G01D02*
X2525384Y927674D01*
G01D02*
X2525414Y927156D01*
G01D02*
X2525445Y926620D01*
G01D02*
X2525476Y926066D01*
G01X2522773Y919556D02*
X2522804Y919120D01*
G01D02*
X2522834Y918713D01*
G01D02*
X2522863Y918334D01*
G01D02*
X2522893Y917982D01*
G01D02*
X2522922Y917657D01*
G01D02*
X2522950Y917359D01*
G01D02*
X2522979Y917089D01*
G01D02*
X2523007Y916846D01*
G01D02*
X2523035Y916630D01*
G01D02*
X2523062Y916439D01*
G01D02*
X2523090Y916271D01*
G01D02*
X2523119Y916123D01*
G01D02*
X2523150Y915993D01*
G01D02*
X2523186Y915874D01*
G01D02*
X2523233Y915755D01*
G01D02*
X2523311Y915620D01*
G01D02*
X2523461Y915471D01*
G01D02*
X2523718Y915362D01*
G01D02*
X2523825Y915352D01*
G01X2526416Y930063D02*
X2526384Y930519D01*
G01D02*
X2526352Y930941D01*
G01D02*
X2526322Y931330D01*
G01D02*
X2526292Y931686D01*
G01D02*
X2526263Y932011D01*
G01D02*
X2526233Y932306D01*
G01D02*
X2526205Y932571D01*
G01D02*
X2526177Y932807D01*
G01D02*
X2526150Y933017D01*
G01D02*
X2526122Y933201D01*
G01D02*
X2526094Y933363D01*
G01D02*
X2526065Y933504D01*
G01D02*
X2526035Y933630D01*
G01D02*
X2525999Y933744D01*
G01D02*
X2525950Y933861D01*
G01D02*
X2525869Y933994D01*
G01D02*
X2525713Y934142D01*
G01D02*
X2525455Y934242D01*
G01D02*
X2525365Y934249D01*
G01X2523331Y930072D02*
X2523300Y930520D01*
G01D02*
X2523269Y930934D01*
G01D02*
X2523239Y931317D01*
G01D02*
X2523210Y931669D01*
G01D02*
X2523181Y931991D01*
G01D02*
X2523152Y932285D01*
G01D02*
X2523124Y932550D01*
G01D02*
X2523096Y932788D01*
G01D02*
X2523069Y932999D01*
G01D02*
X2523041Y933186D01*
G01D02*
X2523013Y933351D01*
G01D02*
X2522984Y933495D01*
G01D02*
X2522953Y933622D01*
G01D02*
X2522918Y933738D01*
G01D02*
X2522870Y933855D01*
G01D02*
X2522789Y933989D01*
G01D02*
X2522635Y934137D01*
G01D02*
X2522375Y934241D01*
G01D02*
X2522282Y934248D01*
G01X2525860Y919517D02*
X2525893Y919046D01*
G01D02*
X2525925Y918618D01*
G01D02*
X2525956Y918229D01*
G01D02*
X2525986Y917875D01*
G01D02*
X2526015Y917556D01*
G01D02*
X2526044Y917267D01*
G01D02*
X2526072Y917007D01*
G01D02*
X2526099Y916775D01*
G01D02*
X2526126Y916570D01*
G01D02*
X2526154Y916389D01*
G01D02*
X2526181Y916230D01*
G01D02*
X2526210Y916089D01*
G01D02*
X2526241Y915966D01*
G01D02*
X2526277Y915852D01*
G01D02*
X2526326Y915736D01*
G01D02*
X2526408Y915604D01*
G01D02*
X2526562Y915459D01*
G01D02*
X2526812Y915361D01*
G01D02*
X2526909Y915353D01*
G01X2520247Y930087D02*
X2520216Y930536D01*
G01D02*
X2520185Y930952D01*
G01D02*
X2520154Y931335D01*
G01D02*
X2520125Y931686D01*
G01D02*
X2520096Y932008D01*
G01D02*
X2520067Y932301D01*
G01D02*
X2520039Y932566D01*
G01D02*
X2520011Y932803D01*
G01D02*
X2519983Y933013D01*
G01D02*
X2519956Y933198D01*
G01D02*
X2519928Y933361D01*
G01D02*
X2519899Y933503D01*
G01X2530001Y916299D02*
X2530008Y916205D01*
G01D02*
X2530015Y916122D01*
G01D02*
X2530022Y916049D01*
G01D02*
X2530030Y915984D01*
G01D02*
X2530039Y915924D01*
G01D02*
X2530051Y915861D01*
G01X2530700Y933315D02*
X2530693Y933406D01*
G01D02*
X2530686Y933487D01*
G01D02*
X2530678Y933559D01*
G01D02*
X2530670Y933624D01*
G01D02*
X2530662Y933683D01*
G01D02*
X2530650Y933743D01*
G01D02*
X2530632Y933813D01*
G01D02*
X2530593Y933912D01*
G01D02*
X2530502Y934048D01*
G01D02*
X2530341Y934176D01*
G01D02*
X2530121Y934246D01*
G01D02*
X2530056Y934250D01*
G01X2528817Y916290D02*
X2528824Y916197D01*
G01D02*
X2528832Y916115D01*
G01D02*
X2528841Y916043D01*
G01D02*
X2528849Y915978D01*
G01D02*
X2528858Y915918D01*
G01D02*
X2528870Y915856D01*
G01D02*
X2528890Y915786D01*
G01D02*
X2528929Y915689D01*
G01D02*
X2529019Y915554D01*
G01D02*
X2529176Y915428D01*
G01D02*
X2529389Y915357D01*
G01X2530001Y916300D02*
X2529994Y916367D01*
G01D02*
X2529987Y916461D01*
G01D02*
X2529979Y916570D01*
G01D02*
X2529971Y916694D01*
G01D02*
X2529962Y916835D01*
G01D02*
X2529954Y916991D01*
G01D02*
X2529944Y917164D01*
G01D02*
X2529934Y917353D01*
G01D02*
X2529924Y917558D01*
G01D02*
X2529914Y917780D01*
G01D02*
X2529904Y918017D01*
G01D02*
X2529893Y918270D01*
G01D02*
X2529881Y918539D01*
G01D02*
X2529870Y918823D01*
G01D02*
X2529858Y919122D01*
G01X2528090Y932391D02*
X2528109Y932170D01*
G01D02*
X2528129Y931926D01*
G01D02*
X2528150Y931657D01*
G01D02*
X2528170Y931362D01*
G01D02*
X2528191Y931041D01*
G01D02*
X2528212Y930696D01*
G01D02*
X2528233Y930329D01*
G01D02*
X2528254Y929941D01*
G01D02*
X2528275Y929535D01*
G01D02*
X2528295Y929115D01*
G01D02*
X2528315Y928682D01*
G01X2531205Y916109D02*
Y916110D01*
G01D02*
X2531201Y916133D01*
G01D02*
X2531196Y916173D01*
G01D02*
X2531191Y916229D01*
G01D02*
X2531185Y916300D01*
G01D02*
X2531178Y916387D01*
G01D02*
X2531171Y916489D01*
G01D02*
X2531164Y916607D01*
G01D02*
X2531157Y916741D01*
G01D02*
X2531150Y916890D01*
G01D02*
X2531142Y917057D01*
G01D02*
X2531134Y917239D01*
G01D02*
X2531126Y917439D01*
G01D02*
X2531118Y917656D01*
G01X2521079Y917118D02*
X2521053Y917355D01*
G01D02*
X2521026Y917619D01*
G01D02*
X2520999Y917910D01*
G01D02*
X2520972Y918228D01*
G01D02*
X2520944Y918572D01*
G01D02*
X2520916Y918944D01*
G01D02*
X2520887Y919343D01*
G01X2526779Y919586D02*
X2526750Y919169D01*
G01D02*
X2526721Y918779D01*
G01D02*
X2526693Y918417D01*
G01D02*
X2526665Y918082D01*
G01D02*
X2526637Y917776D01*
G01D02*
X2526611Y917498D01*
G01D02*
X2526585Y917248D01*
G01D02*
X2526559Y917026D01*
G01D02*
X2526535Y916830D01*
G01D02*
X2526511Y916662D01*
G01D02*
X2526489Y916520D01*
G01D02*
X2526468Y916406D01*
G01D02*
X2526450Y916320D01*
G01D02*
X2526435Y916266D01*
G01D02*
X2526434Y916261D01*
G01X2525493Y929976D02*
X2525521Y930385D01*
G01D02*
X2525549Y930768D01*
G01D02*
X2525577Y931125D01*
G01D02*
X2525604Y931457D01*
G01D02*
X2525631Y931762D01*
G01D02*
X2525657Y932041D01*
G01D02*
X2525683Y932293D01*
G01D02*
X2525708Y932519D01*
G01D02*
X2525732Y932719D01*
G01D02*
X2525756Y932893D01*
G01D02*
X2525778Y933041D01*
G01D02*
X2525800Y933163D01*
G01D02*
X2525819Y933258D01*
G01D02*
X2525835Y933323D01*
G01D02*
X2525837Y933328D01*
G01X2520625Y919777D02*
X2520576Y919074D01*
G01D02*
X2520525Y918411D01*
G01D02*
X2520472Y917801D01*
G01D02*
X2520419Y917258D01*
G01D02*
X2520364Y916802D01*
G01D02*
X2520319Y916502D01*
G01X2523700Y919659D02*
X2523672Y919250D01*
G01D02*
X2523643Y918865D01*
G01D02*
X2523616Y918505D01*
G01D02*
X2523589Y918171D01*
G01D02*
X2523561Y917862D01*
G01D02*
X2523535Y917579D01*
G01D02*
X2523509Y917322D01*
G01D02*
X2523484Y917092D01*
G01D02*
X2523459Y916888D01*
G01D02*
X2523435Y916711D01*
G01D02*
X2523412Y916560D01*
G01D02*
X2523390Y916437D01*
G01D02*
X2523370Y916341D01*
G01D02*
X2523354Y916276D01*
G01D02*
X2523353Y916271D01*
G01X2521237Y930116D02*
X2521229Y930007D01*
G01D02*
X2521195Y929499D01*
G01D02*
X2521161Y928955D01*
G01D02*
X2521125Y928376D01*
G01D02*
X2521089Y927764D01*
G01D02*
X2521051Y927121D01*
G01D02*
X2521013Y926450D01*
G01D02*
X2520974Y925754D01*
G01D02*
X2520934Y925036D01*
G01X2524320Y930116D02*
X2524307Y929924D01*
G01D02*
X2524273Y929417D01*
G01D02*
X2524239Y928872D01*
G01D02*
X2524203Y928288D01*
G01D02*
X2524167Y927671D01*
G01D02*
X2524130Y927030D01*
G01D02*
X2524092Y926374D01*
G01D02*
X2524056Y925713D01*
G01D02*
X2524019Y925057D01*
G01X2524870Y919486D02*
X2524887Y919722D01*
G01D02*
X2524919Y920222D01*
G01D02*
X2524954Y920759D01*
G01D02*
X2524989Y921335D01*
G01D02*
X2525025Y921945D01*
G01D02*
X2525061Y922581D01*
G01D02*
X2525098Y923234D01*
G01D02*
X2525135Y923893D01*
G01D02*
X2525172Y924548D01*
G01X2527404Y930116D02*
X2527378Y929736D01*
G01D02*
X2527336Y929088D01*
G01D02*
X2527295Y928426D01*
G01D02*
X2527256Y927756D01*
G01D02*
X2527217Y927084D01*
G01X2522394Y929762D02*
X2522424Y930194D01*
G01D02*
X2522453Y930600D01*
G01D02*
X2522482Y930977D01*
G01D02*
X2522510Y931328D01*
G01D02*
X2522537Y931650D01*
G01D02*
X2522565Y931946D01*
G01D02*
X2522591Y932215D01*
G01D02*
X2522617Y932456D01*
G01D02*
X2522643Y932670D01*
G01D02*
X2522667Y932857D01*
G01D02*
X2522691Y933016D01*
G01D02*
X2522713Y933146D01*
G01D02*
X2522733Y933248D01*
G01D02*
X2522750Y933319D01*
G01D02*
X2522752Y933326D01*
G01X2527943Y919331D02*
X2527976Y919804D01*
G01D02*
X2528009Y920309D01*
G01D02*
X2528043Y920845D01*
G01D02*
X2528055Y921050D01*
G01X2521787Y919486D02*
X2521819Y919963D01*
G01D02*
X2521862Y920632D01*
G01D02*
X2521904Y921313D01*
G01D02*
X2521944Y922000D01*
G01D02*
X2521984Y922688D01*
G01D02*
X2522023Y923372D01*
G01D02*
X2522097Y924711D01*
G01X2530113Y916331D02*
X2530120Y916442D01*
G01D02*
X2530127Y916565D01*
G01D02*
X2530135Y916702D01*
G01D02*
X2530142Y916852D01*
G01D02*
X2530150Y917015D01*
G01D02*
X2530157Y917193D01*
G01D02*
X2530165Y917383D01*
G01D02*
X2530172Y917589D01*
G01D02*
X2530180Y917807D01*
G01D02*
X2530188Y918041D01*
G01D02*
X2530196Y918288D01*
G01D02*
X2530204Y918549D01*
G01D02*
X2530212Y918824D01*
G01D02*
X2530220Y919112D01*
G01D02*
X2530228Y919414D01*
G01D02*
X2530236Y919728D01*
G01D02*
X2530253Y920395D01*
G01X2529406Y933249D02*
X2529398Y933126D01*
G01D02*
X2529391Y932988D01*
G01D02*
X2529383Y932832D01*
G01D02*
X2529374Y932658D01*
G01D02*
X2529366Y932465D01*
G01D02*
X2529357Y932254D01*
G01D02*
X2529349Y932022D01*
G01D02*
X2529340Y931770D01*
G01D02*
X2529335Y931619D01*
G01X2528473Y928359D02*
X2528518Y929096D01*
G01D02*
X2528565Y929815D01*
G01D02*
X2528614Y930508D01*
G01D02*
X2528664Y931163D01*
G01D02*
X2528715Y931769D01*
G01D02*
X2528769Y932310D01*
G01D02*
X2528822Y932769D01*
G01D02*
X2528867Y933070D01*
G01X2528055Y921050D02*
X2528077Y921413D01*
G01D02*
X2528113Y922011D01*
G01D02*
X2528148Y922639D01*
G01X2522269Y927759D02*
X2522302Y928300D01*
G01D02*
X2522333Y928815D01*
G01D02*
X2522364Y929302D01*
G01D02*
X2522394Y929762D01*
G01X2520765Y922023D02*
X2520719Y921261D01*
G01D02*
X2520673Y920509D01*
G01D02*
X2520625Y919777D01*
G01X2526934Y922058D02*
X2526902Y921513D01*
G01D02*
X2526870Y920993D01*
G01D02*
X2526839Y920498D01*
G01D02*
X2526809Y920029D01*
G01D02*
X2526779Y919586D01*
G01X2525341Y927552D02*
X2525372Y928086D01*
G01D02*
X2525403Y928596D01*
G01D02*
X2525433Y929081D01*
G01D02*
X2525463Y929542D01*
G01D02*
X2525493Y929976D01*
G01X2523851Y922069D02*
X2523820Y921540D01*
G01D02*
X2523789Y921034D01*
G01D02*
X2523759Y920552D01*
G01D02*
X2523729Y920093D01*
G01D02*
X2523700Y919659D01*
G01X2528390Y926946D02*
X2528428Y927614D01*
G01D02*
X2528473Y928359D01*
G01X2527000Y923214D02*
X2526967Y922625D01*
G01D02*
X2526934Y922058D01*
G01X2527217Y927084D02*
X2527178Y926413D01*
G01D02*
X2527141Y925748D01*
G01D02*
X2527105Y925093D01*
G01D02*
X2527069Y924450D01*
G01D02*
X2527034Y923823D01*
G01D02*
X2527000Y923214D01*
G01X2528148Y922639D02*
X2528185Y923293D01*
G01D02*
X2528224Y923972D01*
G01D02*
X2528263Y924672D01*
G01X2525172Y924548D02*
X2525242Y925813D01*
G01D02*
X2525276Y926415D01*
G01D02*
X2525309Y926995D01*
G01D02*
X2525341Y927552D01*
G01X2524019Y925057D02*
X2523949Y923796D01*
G01D02*
X2523915Y923198D01*
G01D02*
X2523883Y922622D01*
G01D02*
X2523851Y922069D01*
G01X2522097Y924711D02*
X2522169Y925992D01*
G01D02*
X2522203Y926604D01*
G01D02*
X2522237Y927193D01*
G01D02*
X2522269Y927759D01*
G01X2520934Y925036D02*
X2520852Y923548D01*
G01D02*
X2520809Y922787D01*
G01D02*
X2520765Y922023D01*
G01X2529322Y931203D02*
X2529312Y930887D01*
G01D02*
X2529302Y930551D01*
G01D02*
X2529293Y930195D01*
G01D02*
X2529283Y929820D01*
G01D02*
X2529273Y929426D01*
G01D02*
X2529263Y929016D01*
G01D02*
X2529243Y928151D01*
G01X2530464Y929799D02*
X2530480Y930394D01*
G01D02*
X2530487Y930670D01*
G01D02*
X2530494Y930931D01*
G01D02*
X2530502Y931180D01*
G01D02*
X2530509Y931413D01*
G01D02*
X2530517Y931635D01*
G01D02*
X2530524Y931843D01*
G01D02*
X2530531Y932037D01*
G01D02*
X2530538Y932219D01*
G01D02*
X2530544Y932389D01*
G01D02*
X2530551Y932545D01*
G01D02*
X2530558Y932689D01*
G01D02*
X2530564Y932820D01*
G01D02*
X2530570Y932940D01*
G01D02*
X2530577Y933047D01*
G01D02*
X2530583Y933143D01*
G01D02*
X2530589Y933227D01*
G01D02*
X2530594Y933300D01*
G01D02*
X2530600Y933363D01*
G01D02*
X2530604Y933414D01*
G01D02*
X2530609Y933454D01*
G01D02*
X2530613Y933484D01*
G01X2529085Y920938D02*
X2529067Y920204D01*
G01D02*
X2529058Y919858D01*
G01D02*
X2529050Y919527D01*
G01D02*
X2529041Y919211D01*
G01D02*
X2529033Y918909D01*
G01D02*
X2529024Y918623D01*
G01D02*
X2529016Y918351D01*
G01D02*
X2529008Y918094D01*
G01D02*
X2529000Y917853D01*
G01D02*
X2528992Y917627D01*
G01D02*
X2528984Y917416D01*
G01D02*
X2528976Y917221D01*
G01D02*
X2528969Y917042D01*
G01D02*
X2528961Y916879D01*
G01D02*
X2528954Y916731D01*
G01D02*
X2528946Y916600D01*
G01D02*
X2528939Y916483D01*
G01D02*
X2528933Y916383D01*
G01D02*
X2528926Y916297D01*
G01D02*
X2528920Y916227D01*
G01D02*
X2528915Y916172D01*
G01D02*
X2528910Y916132D01*
G01D02*
X2528906Y916109D01*
G01X2520636Y923449D02*
X2520566Y924706D01*
G01D02*
X2520493Y926017D01*
G01D02*
X2520456Y926672D01*
G01D02*
X2520419Y927315D01*
G01D02*
X2520383Y927935D01*
G01D02*
X2520348Y928527D01*
G01D02*
X2520313Y929083D01*
G01D02*
X2520280Y929603D01*
G01D02*
X2520247Y930087D01*
G01X2520319Y916501D02*
X2520308Y916444D01*
G01D02*
X2520291Y916356D01*
G01D02*
X2520275Y916292D01*
G01D02*
X2520265Y916254D01*
G01D02*
X2520262Y916246D01*
G01X2528867Y933072D02*
X2528879Y933137D01*
G01D02*
X2528897Y933232D01*
G01D02*
X2528913Y933302D01*
G01D02*
X2528925Y933347D01*
G01D02*
X2528929Y933359D01*
G01X2530613Y933484D02*
X2530615Y933496D01*
G01D02*
X2530613Y933490D01*
G01D02*
X2530604Y933458D01*
G01D02*
X2530574Y933385D01*
G01D02*
X2530497Y933270D01*
G01D02*
X2530348Y933147D01*
G01D02*
X2530134Y933074D01*
G01D02*
X2530056Y933069D01*
G01X2521484Y916325D02*
X2521531Y916630D01*
G01D02*
X2521583Y917061D01*
G01D02*
X2521634Y917555D01*
G01D02*
X2521682Y918101D01*
G01D02*
X2521730Y918691D01*
G01D02*
X2521775Y919314D01*
G01D02*
X2521787Y919486D01*
G01X2527700Y933239D02*
X2527657Y932951D01*
G01D02*
X2527607Y932534D01*
G01D02*
X2527558Y932059D01*
G01D02*
X2527511Y931532D01*
G01D02*
X2527465Y930965D01*
G01D02*
X2527421Y930363D01*
G01D02*
X2527404Y930116D01*
G01X2526434Y916261D02*
X2526430Y916247D01*
G01D02*
X2526441Y916272D01*
G01D02*
X2526493Y916346D01*
G01D02*
X2526617Y916452D01*
G01D02*
X2526834Y916529D01*
G01D02*
X2526908Y916534D01*
G01X2523353Y916271D02*
X2523345Y916246D01*
G01D02*
X2523353Y916263D01*
G01D02*
X2523404Y916339D01*
G01D02*
X2523540Y916455D01*
G01D02*
X2523769Y916531D01*
G01D02*
X2523825Y916533D01*
G01X2525837Y933328D02*
X2525845Y933354D01*
G01D02*
X2525839Y933341D01*
G01D02*
X2525795Y933272D01*
G01D02*
X2525671Y933159D01*
G01D02*
X2525446Y933074D01*
G01D02*
X2525366Y933068D01*
G01X2522752Y933326D02*
X2522761Y933353D01*
G01D02*
X2522755Y933341D01*
G01D02*
X2522711Y933270D01*
G01D02*
X2522584Y933156D01*
G01D02*
X2522358Y933072D01*
G01D02*
X2522282Y933067D01*
G01X2530056Y915844D02*
X2530062Y915870D01*
G01D02*
X2530074Y915932D01*
G01D02*
X2530082Y915996D01*
G01D02*
X2530091Y916065D01*
G01D02*
X2530098Y916143D01*
G01D02*
X2530106Y916231D01*
G01D02*
X2530113Y916331D01*
G01X2529484Y916533D02*
X2529547Y916527D01*
G01D02*
X2529753Y916457D01*
G01D02*
X2529902Y916338D01*
G01D02*
X2529984Y916216D01*
G01D02*
X2530015Y916141D01*
G01D02*
X2530022Y916115D01*
G01X2530659Y916533D02*
X2530730Y916527D01*
G01D02*
X2530938Y916455D01*
G01D02*
X2531087Y916333D01*
G01D02*
X2531169Y916209D01*
G01D02*
X2531198Y916135D01*
G01D02*
X2531205Y916109D01*
G01X2522282Y933067D02*
X2522205Y933073D01*
G01D02*
X2521988Y933152D01*
G01D02*
X2521864Y933259D01*
G01D02*
X2521814Y933332D01*
G01D02*
X2521804Y933353D01*
G01X2526909Y916534D02*
X2526985Y916528D01*
G01D02*
X2527209Y916446D01*
G01D02*
X2527335Y916333D01*
G01D02*
X2527380Y916263D01*
G01D02*
X2527386Y916249D01*
G01X2523825Y916533D02*
X2523901Y916528D01*
G01D02*
X2524127Y916444D01*
G01D02*
X2524253Y916331D01*
G01D02*
X2524297Y916262D01*
G01D02*
X2524303Y916248D01*
G01X2520741Y916534D02*
X2520817Y916529D01*
G01D02*
X2521041Y916446D01*
G01D02*
X2521168Y916333D01*
G01D02*
X2521213Y916263D01*
G01D02*
X2521219Y916249D01*
G01X2525366Y933068D02*
X2525302Y933072D01*
G01D02*
X2525077Y933149D01*
G01D02*
X2524946Y933259D01*
G01D02*
X2524897Y933332D01*
G01D02*
X2524887Y933354D01*
G01X2530056Y933069D02*
X2529990Y933072D01*
G01D02*
X2529779Y933139D01*
G01D02*
X2529624Y933258D01*
G01D02*
X2529538Y933383D01*
G01D02*
X2529506Y933461D01*
G01D02*
X2529497Y933492D01*
G01D02*
X2529496Y933495D01*
G01X2528445Y933069D02*
X2528386Y933072D01*
G01D02*
X2528161Y933146D01*
G01D02*
X2528024Y933260D01*
G01D02*
X2527969Y933342D01*
G01D02*
X2527955Y933371D01*
G01X2520262Y916246D02*
X2520263Y916248D01*
G01D02*
X2520280Y916281D01*
G01D02*
X2520337Y916360D01*
G01D02*
X2520474Y916465D01*
G01D02*
X2520690Y916531D01*
G01D02*
X2520741Y916534D01*
G01X2528929Y933359D02*
X2528930Y933361D01*
G01D02*
X2528919Y933337D01*
G01D02*
X2528870Y933265D01*
G01D02*
X2528745Y933155D01*
G01D02*
X2528524Y933074D01*
G01D02*
X2528445Y933069D01*
G01X2530056Y934250D02*
X2529973Y934244D01*
G01D02*
X2529760Y934170D01*
G01D02*
X2529603Y934041D01*
G01D02*
X2529513Y933900D01*
G01D02*
X2529475Y933798D01*
G01D02*
X2529458Y933728D01*
G01D02*
X2529447Y933666D01*
G01D02*
X2529438Y933602D01*
G01D02*
X2529430Y933531D01*
G01D02*
X2529422Y933450D01*
G01D02*
X2529414Y933357D01*
G01D02*
X2529406Y933249D01*
G01X2528445Y934250D02*
X2528358Y934243D01*
G01D02*
X2528115Y934152D01*
G01D02*
X2527961Y934016D01*
G01D02*
X2527878Y933891D01*
G01D02*
X2527830Y933783D01*
G01D02*
X2527796Y933683D01*
G01D02*
X2527767Y933577D01*
G01D02*
X2527741Y933460D01*
G01D02*
X2527715Y933328D01*
G01D02*
X2527700Y933240D01*
G01X2522282Y934248D02*
X2522183Y934240D01*
G01D02*
X2521933Y934140D01*
G01D02*
X2521779Y933994D01*
G01D02*
X2521698Y933861D01*
G01D02*
X2521649Y933743D01*
G01D02*
X2521613Y933627D01*
G01D02*
X2521582Y933501D01*
G01D02*
X2521554Y933358D01*
G01D02*
X2521526Y933196D01*
G01D02*
X2521498Y933012D01*
G01D02*
X2521471Y932804D01*
G01D02*
X2521443Y932569D01*
G01D02*
X2521415Y932306D01*
G01D02*
X2521386Y932010D01*
G01D02*
X2521356Y931681D01*
G01D02*
X2521326Y931317D01*
G01D02*
X2521294Y930917D01*
G01D02*
X2521262Y930480D01*
G01D02*
X2521237Y930116D01*
G01X2525366Y934249D02*
X2525257Y934239D01*
G01D02*
X2525001Y934130D01*
G01D02*
X2524852Y933980D01*
G01D02*
X2524774Y933846D01*
G01D02*
X2524727Y933728D01*
G01D02*
X2524692Y933610D01*
G01D02*
X2524662Y933481D01*
G01D02*
X2524633Y933334D01*
G01D02*
X2524605Y933166D01*
G01D02*
X2524577Y932974D01*
G01D02*
X2524549Y932756D01*
G01D02*
X2524520Y932511D01*
G01D02*
X2524491Y932235D01*
G01D02*
X2524462Y931930D01*
G01D02*
X2524432Y931595D01*
G01D02*
X2524402Y931228D01*
G01D02*
X2524371Y930828D01*
G01D02*
X2524339Y930393D01*
G01D02*
X2524320Y930116D01*
G01X2526908Y915353D02*
X2526983Y915358D01*
G01D02*
X2527244Y915453D01*
G01D02*
X2527409Y915604D01*
G01D02*
X2527495Y915745D01*
G01D02*
X2527546Y915870D01*
G01D02*
X2527583Y915994D01*
G01D02*
X2527615Y916129D01*
G01D02*
X2527644Y916283D01*
G01D02*
X2527673Y916459D01*
G01D02*
X2527702Y916661D01*
G01D02*
X2527731Y916891D01*
G01D02*
X2527760Y917150D01*
G01D02*
X2527790Y917437D01*
G01D02*
X2527820Y917754D01*
G01D02*
X2527850Y918102D01*
G01D02*
X2527880Y918480D01*
G01D02*
X2527911Y918890D01*
G01D02*
X2527943Y919331D01*
G01X2523824Y915352D02*
X2523911Y915359D01*
G01D02*
X2524173Y915460D01*
G01D02*
X2524332Y915612D01*
G01D02*
X2524415Y915752D01*
G01D02*
X2524463Y915874D01*
G01D02*
X2524500Y915997D01*
G01D02*
X2524531Y916131D01*
G01D02*
X2524560Y916282D01*
G01D02*
X2524589Y916456D01*
G01D02*
X2524617Y916654D01*
G01D02*
X2524646Y916879D01*
G01D02*
X2524674Y917132D01*
G01D02*
X2524704Y917413D01*
G01D02*
X2524733Y917724D01*
G01D02*
X2524763Y918063D01*
G01D02*
X2524793Y918430D01*
G01D02*
X2524823Y918828D01*
G01D02*
X2524854Y919259D01*
G01D02*
X2524870Y919486D01*
G01X2520741Y915353D02*
X2520827Y915359D01*
G01D02*
X2521084Y915457D01*
G01D02*
X2521241Y915603D01*
G01D02*
X2521324Y915737D01*
G01D02*
X2521373Y915854D01*
G01D02*
X2521409Y915969D01*
G01D02*
X2521439Y916093D01*
G01D02*
X2521468Y916233D01*
G01D02*
X2521485Y916326D01*
G01X2528906Y916109D02*
X2528915Y916139D01*
G01D02*
X2528947Y916218D01*
G01D02*
X2529033Y916343D01*
G01D02*
X2529189Y916463D01*
G01D02*
X2529400Y916530D01*
G01D02*
X2529452Y916533D01*
G01X2529532Y915356D02*
X2529746Y915424D01*
G01D02*
X2529908Y915550D01*
G01D02*
X2530003Y915693D01*
G01D02*
X2530044Y915798D01*
G01D02*
X2530056Y915844D01*
G01X2548559Y960234D02*
G03X2544622Y964171I-3937J0D01*
G01X2544587Y1068207D02*
X2556398D01*
G01X2557589Y1071095D02*
X2558239Y1071960D01*
X2558996Y1072394D01*
X2559863Y1072538D01*
X2560945Y1072249D01*
X2561703Y1071528D01*
X2561920Y1070662D01*
X2561811Y1069795D01*
X2561378Y1069074D01*
X2559213Y1067630D01*
X2558239Y1066620D01*
X2557589Y1065176D01*
X2557372Y1063877D01*
X2561920D01*
G01X2566683Y1069651D02*
X2569931Y1063877D01*
G01Y1069651D02*
X2566683Y1063877D01*
G01X2583139D02*
Y1072538D01*
X2588119Y1063877D01*
Y1072538D01*
G01X2594290Y1063877D02*
X2593424Y1064021D01*
X2592666Y1064599D01*
X2592016Y1065465D01*
X2591583Y1066475D01*
X2591367Y1067630D01*
Y1068785D01*
X2591583Y1069940D01*
X2592016Y1070950D01*
X2592666Y1071816D01*
X2593424Y1072394D01*
X2594290Y1072538D01*
X2595156Y1072394D01*
X2595914Y1071816D01*
X2596564Y1070950D01*
X2596997Y1069940D01*
X2597213Y1068785D01*
Y1067630D01*
X2596997Y1066475D01*
X2596564Y1065465D01*
X2595914Y1064599D01*
X2595156Y1064021D01*
X2594290Y1063877D01*
G01X2613994Y1071816D02*
X2613344Y1072249D01*
X2612586Y1072538D01*
X2611720D01*
X2610746Y1072105D01*
X2609988Y1071383D01*
X2609447Y1070517D01*
X2609013Y1069074D01*
X2608905Y1067774D01*
X2609122Y1066475D01*
X2609447Y1065609D01*
X2610096Y1064743D01*
X2610854Y1064166D01*
X2611612Y1063877D01*
X2612370D01*
X2613128Y1064166D01*
X2613777Y1064599D01*
X2614319Y1065176D01*
G01X2620273Y1063877D02*
X2619407Y1064021D01*
X2618649Y1064599D01*
X2617999Y1065465D01*
X2617566Y1066475D01*
X2617350Y1067630D01*
Y1068785D01*
X2617566Y1069940D01*
X2617999Y1070950D01*
X2618649Y1071816D01*
X2619407Y1072394D01*
X2620273Y1072538D01*
X2621139Y1072394D01*
X2621897Y1071816D01*
X2622547Y1070950D01*
X2622980Y1069940D01*
X2623196Y1068785D01*
Y1067630D01*
X2622980Y1066475D01*
X2622547Y1065465D01*
X2621897Y1064599D01*
X2621139Y1064021D01*
X2620273Y1063877D01*
G01X2626119D02*
Y1072538D01*
X2628934Y1065320D01*
X2631749Y1072538D01*
Y1063877D01*
G01X2635430D02*
Y1072538D01*
X2638028D01*
X2638894Y1072105D01*
X2639544Y1071095D01*
X2639760Y1069940D01*
X2639544Y1068785D01*
X2639002Y1067919D01*
X2638028Y1067486D01*
X2635430D01*
G01X2646256Y1063877D02*
X2645390Y1064021D01*
X2644632Y1064599D01*
X2643982Y1065465D01*
X2643549Y1066475D01*
X2643333Y1067630D01*
Y1068785D01*
X2643549Y1069940D01*
X2643982Y1070950D01*
X2644632Y1071816D01*
X2645390Y1072394D01*
X2646256Y1072538D01*
X2647122Y1072394D01*
X2647880Y1071816D01*
X2648530Y1070950D01*
X2648963Y1069940D01*
X2649179Y1068785D01*
Y1067630D01*
X2648963Y1066475D01*
X2648530Y1065465D01*
X2647880Y1064599D01*
X2647122Y1064021D01*
X2646256Y1063877D01*
G01X2652427D02*
Y1072538D01*
X2657407Y1063877D01*
Y1072538D01*
G01X2665743Y1063877D02*
X2661413D01*
Y1072538D01*
X2665743D01*
G01X2664011Y1068352D02*
X2661413D01*
G01X2669749Y1063877D02*
Y1072538D01*
X2674729Y1063877D01*
Y1072538D01*
G01X2680900D02*
Y1063877D01*
G01X2678410Y1072538D02*
X2683390D01*
G01X2701470Y1060990D02*
X2696057Y1069651D01*
Y1071095D01*
X2697139Y1072538D01*
X2698222D01*
X2699305Y1071095D01*
Y1069651D01*
X2698222Y1068207D01*
X2696057Y1066764D01*
X2694974Y1065320D01*
Y1062434D01*
X2696057Y1060990D01*
X2699305D01*
X2701470Y1063877D01*
G01X2715544Y1072538D02*
Y1063877D01*
G01X2713054Y1072538D02*
X2718034D01*
G01X2722040Y1063877D02*
Y1072538D01*
X2724746D01*
X2725612Y1072105D01*
X2726154Y1071528D01*
X2726370Y1070373D01*
X2726154Y1069218D01*
X2725504Y1068496D01*
X2724746Y1068063D01*
X2722040D01*
G01X2724746D02*
X2726370Y1063877D01*
G01X2730159D02*
X2732866Y1072538D01*
X2735573Y1063877D01*
G01X2734598Y1066908D02*
X2731134D01*
G01X2743909Y1071816D02*
X2743259Y1072249D01*
X2742501Y1072538D01*
X2741635D01*
X2740661Y1072105D01*
X2739903Y1071383D01*
X2739362Y1070517D01*
X2738928Y1069074D01*
X2738820Y1067774D01*
X2739037Y1066475D01*
X2739362Y1065609D01*
X2740011Y1064743D01*
X2740769Y1064166D01*
X2741527Y1063877D01*
X2742285D01*
X2743043Y1064166D01*
X2743692Y1064599D01*
X2744234Y1065176D01*
G01X2752353Y1063877D02*
X2748023D01*
Y1072538D01*
X2752353D01*
G01X2750621Y1068352D02*
X2748023D01*
G01X2559646Y1050885D02*
X2558780Y1051029D01*
X2558022Y1051607D01*
X2557372Y1052473D01*
X2556939Y1053483D01*
X2556723Y1054638D01*
Y1055793D01*
X2556939Y1056948D01*
X2557372Y1057958D01*
X2558022Y1058824D01*
X2558780Y1059402D01*
X2559646Y1059546D01*
X2560512Y1059402D01*
X2561270Y1058824D01*
X2561920Y1057958D01*
X2562353Y1056948D01*
X2562569Y1055793D01*
Y1054638D01*
X2562353Y1053483D01*
X2561920Y1052473D01*
X2561270Y1051607D01*
X2560512Y1051029D01*
X2559646Y1050885D01*
G01X2565817D02*
Y1059546D01*
X2570797Y1050885D01*
Y1059546D01*
G01X2588011Y1058824D02*
X2587361Y1059257D01*
X2586603Y1059546D01*
X2585737D01*
X2584763Y1059113D01*
X2584005Y1058391D01*
X2583464Y1057525D01*
X2583030Y1056082D01*
X2582922Y1054782D01*
X2583139Y1053483D01*
X2583464Y1052617D01*
X2584113Y1051751D01*
X2584871Y1051174D01*
X2585629Y1050885D01*
X2586387D01*
X2587145Y1051174D01*
X2587794Y1051607D01*
X2588336Y1052184D01*
G01X2594290Y1050885D02*
X2593424Y1051029D01*
X2592666Y1051607D01*
X2592016Y1052473D01*
X2591583Y1053483D01*
X2591367Y1054638D01*
Y1055793D01*
X2591583Y1056948D01*
X2592016Y1057958D01*
X2592666Y1058824D01*
X2593424Y1059402D01*
X2594290Y1059546D01*
X2595156Y1059402D01*
X2595914Y1058824D01*
X2596564Y1057958D01*
X2596997Y1056948D01*
X2597213Y1055793D01*
Y1054638D01*
X2596997Y1053483D01*
X2596564Y1052473D01*
X2595914Y1051607D01*
X2595156Y1051029D01*
X2594290Y1050885D01*
G01X2600136D02*
Y1059546D01*
X2602951Y1052328D01*
X2605766Y1059546D01*
Y1050885D01*
G01X2609447D02*
Y1059546D01*
X2612045D01*
X2612911Y1059113D01*
X2613561Y1058103D01*
X2613777Y1056948D01*
X2613561Y1055793D01*
X2613019Y1054927D01*
X2612045Y1054494D01*
X2609447D01*
G01X2620273Y1050885D02*
X2619407Y1051029D01*
X2618649Y1051607D01*
X2617999Y1052473D01*
X2617566Y1053483D01*
X2617350Y1054638D01*
Y1055793D01*
X2617566Y1056948D01*
X2617999Y1057958D01*
X2618649Y1058824D01*
X2619407Y1059402D01*
X2620273Y1059546D01*
X2621139Y1059402D01*
X2621897Y1058824D01*
X2622547Y1057958D01*
X2622980Y1056948D01*
X2623196Y1055793D01*
Y1054638D01*
X2622980Y1053483D01*
X2622547Y1052473D01*
X2621897Y1051607D01*
X2621139Y1051029D01*
X2620273Y1050885D01*
G01X2626444D02*
Y1059546D01*
X2631424Y1050885D01*
Y1059546D01*
G01X2639760Y1050885D02*
X2635430D01*
Y1059546D01*
X2639760D01*
G01X2638028Y1055360D02*
X2635430D01*
G01X2643766Y1050885D02*
Y1059546D01*
X2648746Y1050885D01*
Y1059546D01*
G01X2654917D02*
Y1050885D01*
G01X2652427Y1059546D02*
X2657407D01*
G01X2669965Y1052040D02*
X2670832Y1051318D01*
X2671806Y1050885D01*
X2672672D01*
X2673538Y1051318D01*
X2674188Y1052040D01*
X2674513Y1053050D01*
X2674296Y1054061D01*
X2673755Y1054927D01*
X2672780Y1055504D01*
X2671481Y1055793D01*
X2670723Y1056370D01*
X2670398Y1057381D01*
X2670615Y1058391D01*
X2671156Y1059113D01*
X2671914Y1059546D01*
X2672672D01*
X2673430Y1059257D01*
X2674080Y1058536D01*
G01X2679601Y1059546D02*
X2682199D01*
G01X2680900D02*
Y1050885D01*
G01X2679601D02*
X2682199D01*
G01X2687179D02*
Y1059546D01*
X2689344D01*
X2690211Y1059113D01*
X2690860Y1058536D01*
X2691402Y1057670D01*
X2691835Y1056659D01*
X2691943Y1055215D01*
X2691835Y1053772D01*
X2691402Y1052761D01*
X2690860Y1051895D01*
X2690211Y1051318D01*
X2689344Y1050885D01*
X2687179D01*
G01X2700387D02*
X2696057D01*
Y1059546D01*
X2700387D01*
G01X2698655Y1055360D02*
X2696057D01*
G01X2712837Y1050885D02*
X2715544Y1059546D01*
X2718251Y1050885D01*
G01X2717276Y1053916D02*
X2713812D01*
G01X2721715Y1050885D02*
Y1059546D01*
X2726695Y1050885D01*
Y1059546D01*
G01X2730484Y1050885D02*
Y1059546D01*
X2732649D01*
X2733516Y1059113D01*
X2734165Y1058536D01*
X2734707Y1057670D01*
X2735140Y1056659D01*
X2735248Y1055215D01*
X2735140Y1053772D01*
X2734707Y1052761D01*
X2734165Y1051895D01*
X2733516Y1051318D01*
X2732649Y1050885D01*
X2730484D01*
G01X2747914Y1052040D02*
X2748781Y1051318D01*
X2749755Y1050885D01*
X2750621D01*
X2751487Y1051318D01*
X2752137Y1052040D01*
X2752462Y1053050D01*
X2752245Y1054061D01*
X2751704Y1054927D01*
X2750729Y1055504D01*
X2749430Y1055793D01*
X2748672Y1056370D01*
X2748347Y1057381D01*
X2748564Y1058391D01*
X2749105Y1059113D01*
X2749863Y1059546D01*
X2750621D01*
X2751379Y1059257D01*
X2752029Y1058536D01*
G01X2758849Y1050885D02*
X2757983Y1051029D01*
X2757225Y1051607D01*
X2756575Y1052473D01*
X2756142Y1053483D01*
X2755926Y1054638D01*
Y1055793D01*
X2756142Y1056948D01*
X2756575Y1057958D01*
X2757225Y1058824D01*
X2757983Y1059402D01*
X2758849Y1059546D01*
X2759715Y1059402D01*
X2760473Y1058824D01*
X2761123Y1057958D01*
X2761556Y1056948D01*
X2761772Y1055793D01*
Y1054638D01*
X2761556Y1053483D01*
X2761123Y1052473D01*
X2760473Y1051607D01*
X2759715Y1051029D01*
X2758849Y1050885D01*
G01X2765345Y1059546D02*
Y1050885D01*
X2769675D01*
G01X2773789D02*
Y1059546D01*
X2775954D01*
X2776821Y1059113D01*
X2777470Y1058536D01*
X2778012Y1057670D01*
X2778445Y1056659D01*
X2778553Y1055215D01*
X2778445Y1053772D01*
X2778012Y1052761D01*
X2777470Y1051895D01*
X2776821Y1051318D01*
X2775954Y1050885D01*
X2773789D01*
G01X2786997D02*
X2782667D01*
Y1059546D01*
X2786997D01*
G01X2785265Y1055360D02*
X2782667D01*
G01X2791328Y1050885D02*
Y1059546D01*
X2794034D01*
X2794900Y1059113D01*
X2795442Y1058536D01*
X2795658Y1057381D01*
X2795442Y1056226D01*
X2794792Y1055504D01*
X2794034Y1055071D01*
X2791328D01*
G01X2794034D02*
X2795658Y1050885D01*
G01X2808541Y1052040D02*
X2809408Y1051318D01*
X2810382Y1050885D01*
X2811248D01*
X2812114Y1051318D01*
X2812764Y1052040D01*
X2813089Y1053050D01*
X2812872Y1054061D01*
X2812331Y1054927D01*
X2811356Y1055504D01*
X2810057Y1055793D01*
X2809299Y1056370D01*
X2808974Y1057381D01*
X2809191Y1058391D01*
X2809732Y1059113D01*
X2810490Y1059546D01*
X2811248D01*
X2812006Y1059257D01*
X2812656Y1058536D01*
G01X2818177Y1059546D02*
X2820775D01*
G01X2819476D02*
Y1050885D01*
G01X2818177D02*
X2820775D01*
G01X2825755D02*
Y1059546D01*
X2827920D01*
X2828787Y1059113D01*
X2829436Y1058536D01*
X2829978Y1057670D01*
X2830411Y1056659D01*
X2830519Y1055215D01*
X2830411Y1053772D01*
X2829978Y1052761D01*
X2829436Y1051895D01*
X2828787Y1051318D01*
X2827920Y1050885D01*
X2825755D01*
G01X2838963D02*
X2834633D01*
Y1059546D01*
X2838963D01*
G01X2837231Y1055360D02*
X2834633D01*
G01X2560296Y1042223D02*
X2562461D01*
Y1039625D01*
X2561811Y1038759D01*
X2561053Y1038182D01*
X2559971Y1037893D01*
X2558888Y1038182D01*
X2558130Y1038759D01*
X2557481Y1039625D01*
X2557047Y1040636D01*
X2556831Y1041790D01*
Y1042801D01*
X2557047Y1043667D01*
X2557481Y1044678D01*
X2558130Y1045544D01*
X2558780Y1046121D01*
X2559646Y1046554D01*
X2560404D01*
X2561270Y1046265D01*
X2561920Y1045688D01*
G01X2565817Y1037893D02*
Y1046554D01*
X2570797Y1037893D01*
Y1046554D01*
G01X2574586Y1037893D02*
Y1046554D01*
X2576751D01*
X2577618Y1046121D01*
X2578267Y1045544D01*
X2578809Y1044678D01*
X2579242Y1043667D01*
X2579350Y1042223D01*
X2579242Y1040780D01*
X2578809Y1039769D01*
X2578267Y1038903D01*
X2577618Y1038326D01*
X2576751Y1037893D01*
X2574586D01*
G01X2591583D02*
X2594290Y1046554D01*
X2596997Y1037893D01*
G01X2596022Y1040924D02*
X2592558D01*
G01X2605333Y1045832D02*
X2604683Y1046265D01*
X2603925Y1046554D01*
X2603059D01*
X2602085Y1046121D01*
X2601327Y1045399D01*
X2600786Y1044533D01*
X2600352Y1043090D01*
X2600244Y1041790D01*
X2600461Y1040491D01*
X2600786Y1039625D01*
X2601435Y1038759D01*
X2602193Y1038182D01*
X2602951Y1037893D01*
X2603709D01*
X2604467Y1038182D01*
X2605116Y1038615D01*
X2605658Y1039192D01*
G01X2613994Y1045832D02*
X2613344Y1046265D01*
X2612586Y1046554D01*
X2611720D01*
X2610746Y1046121D01*
X2609988Y1045399D01*
X2609447Y1044533D01*
X2609013Y1043090D01*
X2608905Y1041790D01*
X2609122Y1040491D01*
X2609447Y1039625D01*
X2610096Y1038759D01*
X2610854Y1038182D01*
X2611612Y1037893D01*
X2612370D01*
X2613128Y1038182D01*
X2613777Y1038615D01*
X2614319Y1039192D01*
G01X2622438Y1037893D02*
X2618108D01*
Y1046554D01*
X2622438D01*
G01X2620706Y1042368D02*
X2618108D01*
G01X2626769Y1037893D02*
Y1046554D01*
X2629367D01*
X2630233Y1046121D01*
X2630883Y1045111D01*
X2631099Y1043956D01*
X2630883Y1042801D01*
X2630341Y1041935D01*
X2629367Y1041502D01*
X2626769D01*
G01X2637595Y1046554D02*
Y1037893D01*
G01X2635105Y1046554D02*
X2640085D01*
G01X2643549Y1037893D02*
X2646256Y1046554D01*
X2648963Y1037893D01*
G01X2647988Y1040924D02*
X2644524D01*
G01X2655783Y1042512D02*
X2656216Y1042945D01*
X2656541Y1043667D01*
X2656758Y1044678D01*
X2656541Y1045544D01*
X2656108Y1046121D01*
X2655350Y1046554D01*
X2652427D01*
Y1037893D01*
X2656000D01*
X2656758Y1038470D01*
X2657191Y1039336D01*
X2657407Y1040347D01*
X2657191Y1041357D01*
X2656541Y1042223D01*
X2655783Y1042512D01*
X2652427D01*
G01X2661413Y1046554D02*
Y1037893D01*
X2665743D01*
G01X2674404D02*
X2670074D01*
Y1046554D01*
X2674404D01*
G01X2672672Y1042368D02*
X2670074D01*
G01X2520810Y1381446D02*
X2851517D01*
G01X2626167Y-777373D02*
Y-796310D01*
G01X2593085Y-603015D02*
Y-693145D01*
G01X2639382Y-633712D02*
Y-613712D01*
X2636382Y-617712D01*
G01Y-633712D02*
X2642382D01*
G01X2659382Y-634379D02*
X2658882Y-634045D01*
Y-633379D01*
X2659382Y-633045D01*
X2659882Y-633379D01*
Y-634045D01*
X2659382Y-634379D01*
G01X2674632Y-625379D02*
X2676382Y-623045D01*
X2677882Y-621712D01*
X2679882Y-621046D01*
X2681632Y-621712D01*
X2682882Y-623045D01*
X2683882Y-625045D01*
X2684132Y-627379D01*
X2683882Y-629379D01*
X2682882Y-631379D01*
X2681382Y-633045D01*
X2679632Y-633712D01*
X2677632Y-633045D01*
X2675882Y-631046D01*
X2674882Y-628045D01*
X2674632Y-624712D01*
X2675132Y-620379D01*
X2675882Y-618045D01*
X2677132Y-615712D01*
X2678882Y-614045D01*
X2680632Y-613712D01*
X2682382Y-614379D01*
X2683632Y-616045D01*
G01X2691882Y-633712D02*
Y-620379D01*
G01Y-624046D02*
X2692632Y-622379D01*
X2693882Y-621046D01*
X2695632Y-620379D01*
X2697382Y-621046D01*
X2698632Y-622379D01*
X2699382Y-624046D01*
Y-633712D01*
G01Y-624046D02*
X2700132Y-622379D01*
X2701382Y-621046D01*
X2703132Y-620379D01*
X2704882Y-621046D01*
X2706132Y-622379D01*
X2706882Y-624379D01*
Y-633712D01*
G01X2711882D02*
Y-620379D01*
G01Y-624046D02*
X2712632Y-622379D01*
X2713882Y-621046D01*
X2715632Y-620379D01*
X2717382Y-621046D01*
X2718632Y-622379D01*
X2719382Y-624046D01*
Y-633712D01*
G01Y-624046D02*
X2720132Y-622379D01*
X2721382Y-621046D01*
X2723132Y-620379D01*
X2724882Y-621046D01*
X2726132Y-622379D01*
X2726882Y-624379D01*
Y-633712D01*
G01X2607818Y-665148D02*
X2609318Y-663149D01*
X2611068Y-662148D01*
X2613068Y-661815D01*
X2615568Y-662482D01*
X2617318Y-664148D01*
X2617818Y-666148D01*
X2617568Y-668149D01*
X2616568Y-669815D01*
X2611568Y-673148D01*
X2609318Y-675482D01*
X2607818Y-678816D01*
X2607318Y-681815D01*
X2617818D01*
G01X2632568Y-661815D02*
X2630568Y-662482D01*
X2629068Y-664148D01*
X2628068Y-666148D01*
X2627318Y-668815D01*
X2627068Y-671815D01*
X2627318Y-674815D01*
X2628068Y-677482D01*
X2629068Y-679482D01*
X2630568Y-681148D01*
X2632568Y-681815D01*
X2634568Y-681148D01*
X2636068Y-679482D01*
X2637068Y-677482D01*
X2637818Y-674815D01*
X2638068Y-671815D01*
X2637818Y-668815D01*
X2637068Y-666148D01*
X2636068Y-664148D01*
X2634568Y-662482D01*
X2632568Y-661815D01*
G01X2652568Y-681815D02*
Y-661815D01*
X2649568Y-665815D01*
G01Y-681815D02*
X2655568D01*
G01X2675568D02*
Y-661815D01*
X2666318Y-676148D01*
X2678818D01*
G01X2689318Y-675149D02*
X2695818D01*
G01X2712568Y-681815D02*
Y-661815D01*
X2709568Y-665815D01*
G01Y-681815D02*
X2715568D01*
G01X2732568D02*
Y-661815D01*
X2729568Y-665815D01*
G01Y-681815D02*
X2735568D01*
G01X2749318Y-675149D02*
X2755818D01*
G01X2767818Y-665148D02*
X2769318Y-663149D01*
X2771068Y-662148D01*
X2773068Y-661815D01*
X2775568Y-662482D01*
X2777318Y-664148D01*
X2777818Y-666148D01*
X2777568Y-668149D01*
X2776568Y-669815D01*
X2771568Y-673148D01*
X2769318Y-675482D01*
X2767818Y-678816D01*
X2767318Y-681815D01*
X2777818D01*
G01X2792568Y-661815D02*
X2790568Y-662482D01*
X2789068Y-664148D01*
X2788068Y-666148D01*
X2787318Y-668815D01*
X2787068Y-671815D01*
X2787318Y-674815D01*
X2788068Y-677482D01*
X2789068Y-679482D01*
X2790568Y-681148D01*
X2792568Y-681815D01*
X2794568Y-681148D01*
X2796068Y-679482D01*
X2797068Y-677482D01*
X2797818Y-674815D01*
X2798068Y-671815D01*
X2797818Y-668815D01*
X2797068Y-666148D01*
X2796068Y-664148D01*
X2794568Y-662482D01*
X2792568Y-661815D01*
G01X2597564Y847635D02*
X2598322Y847779D01*
X2599188Y848212D01*
X2599729Y848934D01*
X2599946Y849945D01*
X2599729Y850955D01*
X2599080Y851821D01*
X2598105Y852254D01*
X2597023D01*
X2596373Y852543D01*
X2595832Y853265D01*
X2595615Y854275D01*
X2595940Y855286D01*
X2596698Y856007D01*
X2597564Y856296D01*
X2598430Y856007D01*
X2599188Y855286D01*
X2599513Y854275D01*
X2599296Y853265D01*
X2598755Y852543D01*
X2598105Y852254D01*
X2597023D01*
X2596048Y851821D01*
X2595399Y850955D01*
X2595182Y849945D01*
X2595399Y848934D01*
X2595940Y848212D01*
X2596806Y847779D01*
X2597564Y847635D01*
G01X2604384Y848645D02*
X2605142Y847924D01*
X2606008Y847635D01*
X2606875Y847924D01*
X2607632Y848790D01*
X2608174Y850089D01*
X2608390Y851388D01*
Y852976D01*
X2608174Y854275D01*
X2607632Y855430D01*
X2606983Y856007D01*
X2606225Y856296D01*
X2605359Y856007D01*
X2604709Y855430D01*
X2604276Y854564D01*
X2604060Y853409D01*
X2604276Y852399D01*
X2604818Y851388D01*
X2605467Y850811D01*
X2606225Y850666D01*
X2607091Y850955D01*
X2607741Y851677D01*
X2608390Y852976D01*
G01X2614886Y847346D02*
X2614669Y847491D01*
Y847779D01*
X2614886Y847924D01*
X2615103Y847779D01*
Y847491D01*
X2614886Y847346D01*
G01X2623547Y847635D02*
X2624305Y847779D01*
X2625171Y848212D01*
X2625712Y848934D01*
X2625929Y849945D01*
X2625712Y850955D01*
X2625063Y851821D01*
X2624088Y852254D01*
X2623006D01*
X2622356Y852543D01*
X2621815Y853265D01*
X2621598Y854275D01*
X2621923Y855286D01*
X2622681Y856007D01*
X2623547Y856296D01*
X2624413Y856007D01*
X2625171Y855286D01*
X2625496Y854275D01*
X2625279Y853265D01*
X2624738Y852543D01*
X2624088Y852254D01*
X2623006D01*
X2622031Y851821D01*
X2621382Y850955D01*
X2621165Y849945D01*
X2621382Y848934D01*
X2621923Y848212D01*
X2622789Y847779D01*
X2623547Y847635D01*
G01X2629826Y848934D02*
X2630476Y848212D01*
X2631234Y847779D01*
X2632208Y847635D01*
X2633182Y847924D01*
X2633940Y848501D01*
X2634482Y849511D01*
X2634590Y850666D01*
X2634373Y851821D01*
X2633832Y852543D01*
X2633074Y853120D01*
X2632316Y853265D01*
X2631558Y853120D01*
X2630584Y852543D01*
X2630909Y856296D01*
X2633832D01*
G01X2595723Y873449D02*
X2596481Y872728D01*
X2597347Y872439D01*
X2598214Y872728D01*
X2598971Y873594D01*
X2599513Y874893D01*
X2599729Y876192D01*
Y877780D01*
X2599513Y879079D01*
X2598971Y880234D01*
X2598322Y880811D01*
X2597564Y881100D01*
X2596698Y880811D01*
X2596048Y880234D01*
X2595615Y879368D01*
X2595399Y878213D01*
X2595615Y877203D01*
X2596157Y876192D01*
X2596806Y875615D01*
X2597564Y875470D01*
X2598430Y875759D01*
X2599080Y876481D01*
X2599729Y877780D01*
G01X2604168Y876048D02*
X2604926Y877058D01*
X2605575Y877636D01*
X2606442Y877924D01*
X2607199Y877636D01*
X2607741Y877058D01*
X2608174Y876192D01*
X2608282Y875182D01*
X2608174Y874315D01*
X2607741Y873449D01*
X2607091Y872728D01*
X2606333Y872439D01*
X2605467Y872728D01*
X2604709Y873594D01*
X2604276Y874893D01*
X2604168Y876336D01*
X2604384Y878213D01*
X2604709Y879224D01*
X2605251Y880234D01*
X2606008Y880956D01*
X2606766Y881100D01*
X2607524Y880811D01*
X2608066Y880090D01*
G01X2614886Y872150D02*
X2614669Y872295D01*
Y872583D01*
X2614886Y872728D01*
X2615103Y872583D01*
Y872295D01*
X2614886Y872150D01*
G01X2623547Y872439D02*
Y881100D01*
X2622248Y879368D01*
G01Y872439D02*
X2624846D01*
G01X2629826Y873738D02*
X2630476Y873016D01*
X2631234Y872583D01*
X2632208Y872439D01*
X2633182Y872728D01*
X2633940Y873305D01*
X2634482Y874315D01*
X2634590Y875470D01*
X2634373Y876625D01*
X2633832Y877347D01*
X2633074Y877924D01*
X2632316Y878069D01*
X2631558Y877924D01*
X2630584Y877347D01*
X2630909Y881100D01*
X2633832D01*
G01X2626167Y1400383D02*
Y1381446D01*
G01X2734277Y-792523D02*
Y-776923D01*
X2731937Y-780043D01*
G01Y-792523D02*
X2736617D01*
G01X2754517D02*
Y-776923D01*
X2747302Y-788103D01*
X2757052D01*
G01X2734277Y1385233D02*
Y1400833D01*
X2731937Y1397713D01*
G01Y1385233D02*
X2736617D01*
G01X2754517D02*
Y1400833D01*
X2747302Y1389653D01*
X2757052D01*
G01X2784437Y-753628D02*
X2822042D01*
G01X2851519Y-632688D02*
Y-777373D01*
G01X2851517Y1381446D02*
Y-777373D01*
G01X2822042Y-753628D02*
Y-556309D01*
G01X2858960Y-671993D02*
X2859935Y-673553D01*
X2861105Y-674593D01*
X2862470Y-675113D01*
X2864030Y-674593D01*
X2865200Y-673553D01*
X2866370Y-671993D01*
X2866760Y-669913D01*
Y-659513D01*
G01X2822042Y-556309D02*
Y-497938D01*
G01X2851517Y-561491D02*
X2870454D01*
G01X2860520Y-443630D02*
X2865200D01*
G01X2862860D02*
Y-459230D01*
G01X2860520D02*
X2865200D01*
G01X2851517Y-345608D02*
X2870454D01*
G01X2858765Y-243539D02*
Y-227939D01*
G01X2866955D02*
Y-243539D01*
G01Y-235739D02*
X2858765D01*
G01X2851517Y-129727D02*
X2870454D01*
G01X2864030Y-19856D02*
X2867930D01*
Y-24536D01*
X2866760Y-26096D01*
X2865395Y-27136D01*
X2863445Y-27656D01*
X2861495Y-27136D01*
X2860130Y-26096D01*
X2858960Y-24536D01*
X2858180Y-22716D01*
X2857790Y-20636D01*
Y-18816D01*
X2858180Y-17256D01*
X2858960Y-15436D01*
X2860130Y-13876D01*
X2861300Y-12836D01*
X2862860Y-12056D01*
X2864225D01*
X2865785Y-12576D01*
X2866955Y-13616D01*
G01X2851517Y86155D02*
X2870454D01*
G01X2858775Y188415D02*
Y204015D01*
X2866185D01*
G01X2863455Y196475D02*
X2858775D01*
G01X2851517Y302037D02*
X2870454D01*
G01X2866760Y404486D02*
X2858960D01*
Y420086D01*
X2866760D01*
G01X2863640Y412546D02*
X2858960D01*
G01X2851517Y517918D02*
X2870454D01*
G01X2858570Y620179D02*
Y635779D01*
X2862470D01*
X2864030Y634999D01*
X2865200Y633959D01*
X2866175Y632399D01*
X2866955Y630579D01*
X2867150Y627979D01*
X2866955Y625379D01*
X2866175Y623559D01*
X2865200Y621999D01*
X2864030Y620959D01*
X2862470Y620179D01*
X2858570D01*
G01X2851517Y733800D02*
X2870454D01*
G01X2867150Y850550D02*
X2865980Y851330D01*
X2864615Y851850D01*
X2863055D01*
X2861300Y851070D01*
X2859935Y849770D01*
X2858960Y848210D01*
X2858180Y845610D01*
X2857985Y843270D01*
X2858375Y840930D01*
X2858960Y839370D01*
X2860130Y837810D01*
X2861495Y836770D01*
X2862860Y836250D01*
X2864225D01*
X2865590Y836770D01*
X2866760Y837550D01*
X2867735Y838590D01*
G01X2851517Y949683D02*
X2870454D01*
G01X2864420Y1060262D02*
X2865200Y1061042D01*
X2865785Y1062342D01*
X2866175Y1064162D01*
X2865785Y1065722D01*
X2865005Y1066762D01*
X2863640Y1067542D01*
X2858375D01*
Y1051942D01*
X2864810D01*
X2866175Y1052982D01*
X2866955Y1054542D01*
X2867345Y1056362D01*
X2866955Y1058182D01*
X2865785Y1059742D01*
X2864420Y1060262D01*
X2858375D01*
G01X2851328Y1165564D02*
X2870265D01*
G01X2851517Y1381446D02*
Y1286959D01*
G01X2857985Y1267824D02*
X2862860Y1283424D01*
X2867735Y1267824D01*
G01X2865980Y1273284D02*
X2859740D01*
G01X2870454Y1400383D02*
Y-796310D01*
M02*
